FILE_TYPE = MACRO_DRAWING;
SET COLOR_WIRE YELLOW;
SET COLOR_PROP ORANGE;
SET COLOR_DOT WHITE;
SET COLOR_ARC YELLOW;
SET COLOR_BODY GREEN;
SET COLOR_NOTE PURPLE;
SET PROP_DISPLAY VALUE;
SET PAGE_NUMBER P72;
FORCEADD Q_CAP..1
(-9400 1325);
FORCEPROP 1 LAST LOCATION C2298
J 0
(-9350 1425);
DISPLAY 0.489362 (-9350 1425);
PAINT SKYBLUE (-9350 1425);
FORCEPROP 2 LAST $SEC 1
J 0
(-9350 1525);
DISPLAY 0.680851 (-9350 1525);
PAINT MONO (-9350 1525);
DISPLAY INVISIBLE (-9350 1525);
FORCEPROP 2 LAST CDS_SEC 1
J 0
(-9350 1525);
DISPLAY 1.021277 (-9350 1525);
DISPLAY INVISIBLE (-9350 1525);
FORCEPROP 1 LASTPIN (-9400 1425) $PN 1
J 0
(-9390 1405);
DISPLAY 0.489362 (-9390 1405);
FORCEPROP 1 LASTPIN (-9400 1225) $PN 2
J 0
(-9390 1205);
DISPLAY 0.489362 (-9390 1205);
FORCEPROP 1 LAST MATERIAL X6S
J 0
(-9350 1225);
DISPLAY 0.489362 (-9350 1225);
PAINT SKYBLUE (-9350 1225);
FORCEPROP 1 LAST TOLERANCE 20%
J 0
(-9350 1275);
DISPLAY 0.489362 (-9350 1275);
PAINT SKYBLUE (-9350 1275);
FORCEPROP 1 LAST VALUE 22UF
J 0
(-9350 1375);
DISPLAY 0.489362 (-9350 1375);
PAINT SKYBLUE (-9350 1375);
FORCEPROP 1 LAST PART_NUMBER CH622KMEB02
J 0
(-9350 1175);
DISPLAY 0.489362 (-9350 1175);
PAINT SKYBLUE (-9350 1175);
FORCEPROP 1 LAST VOLTAGE 4V
J 0
(-9350 1325);
DISPLAY 0.489362 (-9350 1325);
PAINT SKYBLUE (-9350 1325);
FORCEPROP 1 LAST PACK_TYPE C0402
J 0
(-9350 1125);
DISPLAY 0.489362 (-9350 1125);
PAINT SKYBLUE (-9350 1125);
FORCEPROP 2 LAST CDS_LIB pure_quanta
J 0
(-9400 1325);
PAINT MONO (-9400 1325);
DISPLAY INVISIBLE (-9400 1325);
FORCEPROP 1 LAST PATH I1
J 0
(-9350 1475);
DISPLAY 0.978723 (-9350 1475);
PAINT WHITE (-9350 1475);
DISPLAY INVISIBLE (-9350 1475);
FORCEADD Q_CAP..1
(-8950 2125);
FORCEPROP 1 LAST LOCATION C2303
J 0
(-8900 2225);
DISPLAY 0.489362 (-8900 2225);
PAINT SKYBLUE (-8900 2225);
FORCEPROP 2 LAST $SEC 1
J 0
(-8900 2325);
DISPLAY 0.680851 (-8900 2325);
PAINT MONO (-8900 2325);
DISPLAY INVISIBLE (-8900 2325);
FORCEPROP 2 LAST CDS_SEC 1
J 0
(-8900 2325);
DISPLAY 1.021277 (-8900 2325);
DISPLAY INVISIBLE (-8900 2325);
FORCEPROP 1 LASTPIN (-8950 2225) $PN 1
J 0
(-8940 2205);
DISPLAY 0.489362 (-8940 2205);
FORCEPROP 1 LASTPIN (-8950 2025) $PN 2
J 0
(-8940 2005);
DISPLAY 0.489362 (-8940 2005);
FORCEPROP 1 LAST MATERIAL X6S
J 0
(-8900 2025);
DISPLAY 0.489362 (-8900 2025);
PAINT SKYBLUE (-8900 2025);
FORCEPROP 1 LAST TOLERANCE 20%
J 0
(-8900 2075);
DISPLAY 0.489362 (-8900 2075);
PAINT SKYBLUE (-8900 2075);
FORCEPROP 1 LAST VALUE 22UF
J 0
(-8900 2175);
DISPLAY 0.489362 (-8900 2175);
PAINT SKYBLUE (-8900 2175);
FORCEPROP 1 LAST PART_NUMBER CH622KMEB02
J 0
(-8900 1975);
DISPLAY 0.489362 (-8900 1975);
PAINT SKYBLUE (-8900 1975);
FORCEPROP 1 LAST VOLTAGE 4V
J 0
(-8900 2125);
DISPLAY 0.489362 (-8900 2125);
PAINT SKYBLUE (-8900 2125);
FORCEPROP 1 LAST PACK_TYPE C0402
J 0
(-8900 1925);
DISPLAY 0.489362 (-8900 1925);
PAINT SKYBLUE (-8900 1925);
FORCEPROP 2 LAST CDS_LIB pure_quanta
J 0
(-8950 2125);
PAINT MONO (-8950 2125);
DISPLAY INVISIBLE (-8950 2125);
FORCEPROP 1 LAST PATH I10
J 0
(-8900 2275);
DISPLAY 0.978723 (-8900 2275);
PAINT WHITE (-8900 2275);
DISPLAY INVISIBLE (-8900 2275);
FORCEADD Q_CAP..1
(-825 3725);
FORCEPROP 1 LAST LOCATION C2403
J 0
(-775 3825);
DISPLAY 0.489362 (-775 3825);
PAINT SKYBLUE (-775 3825);
FORCEPROP 2 LAST $SEC 1
J 0
(-775 3925);
DISPLAY 0.680851 (-775 3925);
PAINT MONO (-775 3925);
DISPLAY INVISIBLE (-775 3925);
FORCEPROP 2 LAST CDS_SEC 1
J 0
(-775 3925);
DISPLAY 1.021277 (-775 3925);
DISPLAY INVISIBLE (-775 3925);
FORCEPROP 1 LASTPIN (-825 3825) $PN 1
J 0
(-815 3805);
DISPLAY 0.489362 (-815 3805);
FORCEPROP 1 LASTPIN (-825 3625) $PN 2
J 0
(-815 3605);
DISPLAY 0.489362 (-815 3605);
FORCEPROP 1 LAST MATERIAL X6S
J 0
(-775 3625);
DISPLAY 0.489362 (-775 3625);
PAINT SKYBLUE (-775 3625);
FORCEPROP 1 LAST TOLERANCE 20%
J 0
(-775 3675);
DISPLAY 0.489362 (-775 3675);
PAINT SKYBLUE (-775 3675);
FORCEPROP 1 LAST VALUE 22UF
J 0
(-775 3775);
DISPLAY 0.489362 (-775 3775);
PAINT SKYBLUE (-775 3775);
FORCEPROP 1 LAST PART_NUMBER CH622KMEB02
J 0
(-775 3575);
DISPLAY 0.489362 (-775 3575);
PAINT SKYBLUE (-775 3575);
FORCEPROP 1 LAST VOLTAGE 4V
J 0
(-775 3725);
DISPLAY 0.489362 (-775 3725);
PAINT SKYBLUE (-775 3725);
FORCEPROP 1 LAST PACK_TYPE C0402
J 0
(-775 3525);
DISPLAY 0.489362 (-775 3525);
PAINT SKYBLUE (-775 3525);
FORCEPROP 2 LAST CDS_LIB pure_quanta
J 0
(-825 3725);
PAINT MONO (-825 3725);
DISPLAY INVISIBLE (-825 3725);
FORCEPROP 1 LAST PATH I100
J 0
(-775 3875);
DISPLAY 0.978723 (-775 3875);
PAINT WHITE (-775 3875);
DISPLAY INVISIBLE (-775 3875);
FORCEADD Q_CAP..1
(-3925 4500);
FORCEPROP 1 LAST LOCATION C2362
J 0
(-3875 4600);
DISPLAY 0.489362 (-3875 4600);
PAINT SKYBLUE (-3875 4600);
FORCEPROP 2 LAST $SEC 1
J 0
(-3875 4700);
DISPLAY 0.680851 (-3875 4700);
PAINT MONO (-3875 4700);
DISPLAY INVISIBLE (-3875 4700);
FORCEPROP 2 LAST CDS_SEC 1
J 0
(-3875 4700);
DISPLAY 1.021277 (-3875 4700);
DISPLAY INVISIBLE (-3875 4700);
FORCEPROP 1 LASTPIN (-3925 4600) $PN 1
J 0
(-3915 4580);
DISPLAY 0.489362 (-3915 4580);
FORCEPROP 1 LASTPIN (-3925 4400) $PN 2
J 0
(-3915 4380);
DISPLAY 0.489362 (-3915 4380);
FORCEPROP 1 LAST MATERIAL X6S
J 0
(-3875 4400);
DISPLAY 0.489362 (-3875 4400);
PAINT SKYBLUE (-3875 4400);
FORCEPROP 1 LAST TOLERANCE 20%
J 0
(-3875 4450);
DISPLAY 0.489362 (-3875 4450);
PAINT SKYBLUE (-3875 4450);
FORCEPROP 1 LAST VALUE 22UF
J 0
(-3875 4550);
DISPLAY 0.489362 (-3875 4550);
PAINT SKYBLUE (-3875 4550);
FORCEPROP 1 LAST PART_NUMBER CH622KMEB02
J 0
(-3875 4350);
DISPLAY 0.489362 (-3875 4350);
PAINT SKYBLUE (-3875 4350);
FORCEPROP 1 LAST VOLTAGE 4V
J 0
(-3875 4500);
DISPLAY 0.489362 (-3875 4500);
PAINT SKYBLUE (-3875 4500);
FORCEPROP 1 LAST PACK_TYPE C0402
J 0
(-3875 4300);
DISPLAY 0.489362 (-3875 4300);
PAINT SKYBLUE (-3875 4300);
FORCEPROP 2 LAST CDS_LIB pure_quanta
J 0
(-3925 4500);
PAINT MONO (-3925 4500);
DISPLAY INVISIBLE (-3925 4500);
FORCEPROP 1 LAST PATH I101
J 0
(-3875 4650);
DISPLAY 0.978723 (-3875 4650);
PAINT WHITE (-3875 4650);
DISPLAY INVISIBLE (-3875 4650);
FORCEADD Q_CAP..1
(-3475 4500);
FORCEPROP 1 LAST LOCATION C2368
J 0
(-3425 4600);
DISPLAY 0.489362 (-3425 4600);
PAINT SKYBLUE (-3425 4600);
FORCEPROP 2 LAST $SEC 1
J 0
(-3425 4700);
DISPLAY 0.680851 (-3425 4700);
PAINT MONO (-3425 4700);
DISPLAY INVISIBLE (-3425 4700);
FORCEPROP 2 LAST CDS_SEC 1
J 0
(-3425 4700);
DISPLAY 1.021277 (-3425 4700);
DISPLAY INVISIBLE (-3425 4700);
FORCEPROP 1 LASTPIN (-3475 4600) $PN 1
J 0
(-3465 4580);
DISPLAY 0.489362 (-3465 4580);
FORCEPROP 1 LASTPIN (-3475 4400) $PN 2
J 0
(-3465 4380);
DISPLAY 0.489362 (-3465 4380);
FORCEPROP 1 LAST MATERIAL X6S
J 0
(-3425 4400);
DISPLAY 0.489362 (-3425 4400);
PAINT SKYBLUE (-3425 4400);
FORCEPROP 1 LAST TOLERANCE 20%
J 0
(-3425 4450);
DISPLAY 0.489362 (-3425 4450);
PAINT SKYBLUE (-3425 4450);
FORCEPROP 1 LAST VALUE 22UF
J 0
(-3425 4550);
DISPLAY 0.489362 (-3425 4550);
PAINT SKYBLUE (-3425 4550);
FORCEPROP 1 LAST PART_NUMBER CH622KMEB02
J 0
(-3425 4350);
DISPLAY 0.489362 (-3425 4350);
PAINT SKYBLUE (-3425 4350);
FORCEPROP 1 LAST VOLTAGE 4V
J 0
(-3425 4500);
DISPLAY 0.489362 (-3425 4500);
PAINT SKYBLUE (-3425 4500);
FORCEPROP 1 LAST PACK_TYPE C0402
J 0
(-3425 4300);
DISPLAY 0.489362 (-3425 4300);
PAINT SKYBLUE (-3425 4300);
FORCEPROP 2 LAST CDS_LIB pure_quanta
J 0
(-3475 4500);
PAINT MONO (-3475 4500);
DISPLAY INVISIBLE (-3475 4500);
FORCEPROP 1 LAST PATH I102
J 0
(-3425 4650);
DISPLAY 0.978723 (-3425 4650);
PAINT WHITE (-3425 4650);
DISPLAY INVISIBLE (-3425 4650);
FORCEADD Q_CAP..1
(-3025 4500);
FORCEPROP 1 LAST LOCATION C2374
J 0
(-2975 4600);
DISPLAY 0.489362 (-2975 4600);
PAINT SKYBLUE (-2975 4600);
FORCEPROP 2 LAST $SEC 1
J 0
(-2975 4700);
DISPLAY 0.680851 (-2975 4700);
PAINT MONO (-2975 4700);
DISPLAY INVISIBLE (-2975 4700);
FORCEPROP 2 LAST CDS_SEC 1
J 0
(-2975 4700);
DISPLAY 1.021277 (-2975 4700);
DISPLAY INVISIBLE (-2975 4700);
FORCEPROP 1 LASTPIN (-3025 4600) $PN 1
J 0
(-3015 4580);
DISPLAY 0.489362 (-3015 4580);
FORCEPROP 1 LASTPIN (-3025 4400) $PN 2
J 0
(-3015 4380);
DISPLAY 0.489362 (-3015 4380);
FORCEPROP 1 LAST MATERIAL X6S
J 0
(-2975 4400);
DISPLAY 0.489362 (-2975 4400);
PAINT SKYBLUE (-2975 4400);
FORCEPROP 1 LAST TOLERANCE 20%
J 0
(-2975 4450);
DISPLAY 0.489362 (-2975 4450);
PAINT SKYBLUE (-2975 4450);
FORCEPROP 1 LAST VALUE 22UF
J 0
(-2975 4550);
DISPLAY 0.489362 (-2975 4550);
PAINT SKYBLUE (-2975 4550);
FORCEPROP 1 LAST PART_NUMBER CH622KMEB02
J 0
(-2975 4350);
DISPLAY 0.489362 (-2975 4350);
PAINT SKYBLUE (-2975 4350);
FORCEPROP 1 LAST VOLTAGE 4V
J 0
(-2975 4500);
DISPLAY 0.489362 (-2975 4500);
PAINT SKYBLUE (-2975 4500);
FORCEPROP 1 LAST PACK_TYPE C0402
J 0
(-2975 4300);
DISPLAY 0.489362 (-2975 4300);
PAINT SKYBLUE (-2975 4300);
FORCEPROP 2 LAST CDS_LIB pure_quanta
J 0
(-3025 4500);
PAINT MONO (-3025 4500);
DISPLAY INVISIBLE (-3025 4500);
FORCEPROP 1 LAST PATH I103
J 0
(-2975 4650);
DISPLAY 0.978723 (-2975 4650);
PAINT WHITE (-2975 4650);
DISPLAY INVISIBLE (-2975 4650);
FORCEADD Q_CAP..1
(-2575 4500);
FORCEPROP 1 LAST LOCATION C2380
J 0
(-2525 4600);
DISPLAY 0.489362 (-2525 4600);
PAINT SKYBLUE (-2525 4600);
FORCEPROP 2 LAST $SEC 1
J 0
(-2525 4700);
DISPLAY 0.680851 (-2525 4700);
PAINT MONO (-2525 4700);
DISPLAY INVISIBLE (-2525 4700);
FORCEPROP 2 LAST CDS_SEC 1
J 0
(-2525 4700);
DISPLAY 1.021277 (-2525 4700);
DISPLAY INVISIBLE (-2525 4700);
FORCEPROP 1 LASTPIN (-2575 4600) $PN 1
J 0
(-2565 4580);
DISPLAY 0.489362 (-2565 4580);
FORCEPROP 1 LASTPIN (-2575 4400) $PN 2
J 0
(-2565 4380);
DISPLAY 0.489362 (-2565 4380);
FORCEPROP 1 LAST MATERIAL X6S
J 0
(-2525 4400);
DISPLAY 0.489362 (-2525 4400);
PAINT SKYBLUE (-2525 4400);
FORCEPROP 1 LAST TOLERANCE 20%
J 0
(-2525 4450);
DISPLAY 0.489362 (-2525 4450);
PAINT SKYBLUE (-2525 4450);
FORCEPROP 1 LAST VALUE 22UF
J 0
(-2525 4550);
DISPLAY 0.489362 (-2525 4550);
PAINT SKYBLUE (-2525 4550);
FORCEPROP 1 LAST PART_NUMBER CH622KMEB02
J 0
(-2525 4350);
DISPLAY 0.489362 (-2525 4350);
PAINT SKYBLUE (-2525 4350);
FORCEPROP 1 LAST VOLTAGE 4V
J 0
(-2525 4500);
DISPLAY 0.489362 (-2525 4500);
PAINT SKYBLUE (-2525 4500);
FORCEPROP 1 LAST PACK_TYPE C0402
J 0
(-2525 4300);
DISPLAY 0.489362 (-2525 4300);
PAINT SKYBLUE (-2525 4300);
FORCEPROP 2 LAST CDS_LIB pure_quanta
J 0
(-2575 4500);
PAINT MONO (-2575 4500);
DISPLAY INVISIBLE (-2575 4500);
FORCEPROP 1 LAST PATH I104
J 0
(-2525 4650);
DISPLAY 0.978723 (-2525 4650);
PAINT WHITE (-2525 4650);
DISPLAY INVISIBLE (-2525 4650);
FORCEADD Q_CAP..1
(-2125 4500);
FORCEPROP 1 LAST LOCATION C2386
J 0
(-2075 4600);
DISPLAY 0.489362 (-2075 4600);
PAINT SKYBLUE (-2075 4600);
FORCEPROP 2 LAST $SEC 1
J 0
(-2075 4700);
DISPLAY 0.680851 (-2075 4700);
PAINT MONO (-2075 4700);
DISPLAY INVISIBLE (-2075 4700);
FORCEPROP 2 LAST CDS_SEC 1
J 0
(-2075 4700);
DISPLAY 1.021277 (-2075 4700);
DISPLAY INVISIBLE (-2075 4700);
FORCEPROP 1 LASTPIN (-2125 4600) $PN 1
J 0
(-2115 4580);
DISPLAY 0.489362 (-2115 4580);
FORCEPROP 1 LASTPIN (-2125 4400) $PN 2
J 0
(-2115 4380);
DISPLAY 0.489362 (-2115 4380);
FORCEPROP 1 LAST MATERIAL X6S
J 0
(-2075 4400);
DISPLAY 0.489362 (-2075 4400);
PAINT SKYBLUE (-2075 4400);
FORCEPROP 1 LAST TOLERANCE 20%
J 0
(-2075 4450);
DISPLAY 0.489362 (-2075 4450);
PAINT SKYBLUE (-2075 4450);
FORCEPROP 1 LAST VALUE 22UF
J 0
(-2075 4550);
DISPLAY 0.489362 (-2075 4550);
PAINT SKYBLUE (-2075 4550);
FORCEPROP 1 LAST PART_NUMBER CH622KMEB02
J 0
(-2075 4350);
DISPLAY 0.489362 (-2075 4350);
PAINT SKYBLUE (-2075 4350);
FORCEPROP 1 LAST VOLTAGE 4V
J 0
(-2075 4500);
DISPLAY 0.489362 (-2075 4500);
PAINT SKYBLUE (-2075 4500);
FORCEPROP 1 LAST PACK_TYPE C0402
J 0
(-2075 4300);
DISPLAY 0.489362 (-2075 4300);
PAINT SKYBLUE (-2075 4300);
FORCEPROP 2 LAST CDS_LIB pure_quanta
J 0
(-2125 4500);
PAINT MONO (-2125 4500);
DISPLAY INVISIBLE (-2125 4500);
FORCEPROP 1 LAST PATH I105
J 0
(-2075 4650);
DISPLAY 0.978723 (-2075 4650);
PAINT WHITE (-2075 4650);
DISPLAY INVISIBLE (-2075 4650);
FORCEADD Q_CAP..1
(-1675 4500);
FORCEPROP 1 LAST LOCATION C2392
J 0
(-1625 4600);
DISPLAY 0.489362 (-1625 4600);
PAINT SKYBLUE (-1625 4600);
FORCEPROP 2 LAST $SEC 1
J 0
(-1625 4700);
DISPLAY 0.680851 (-1625 4700);
PAINT MONO (-1625 4700);
DISPLAY INVISIBLE (-1625 4700);
FORCEPROP 2 LAST CDS_SEC 1
J 0
(-1625 4700);
DISPLAY 1.021277 (-1625 4700);
DISPLAY INVISIBLE (-1625 4700);
FORCEPROP 1 LASTPIN (-1675 4600) $PN 1
J 0
(-1665 4580);
DISPLAY 0.489362 (-1665 4580);
FORCEPROP 1 LASTPIN (-1675 4400) $PN 2
J 0
(-1665 4380);
DISPLAY 0.489362 (-1665 4380);
FORCEPROP 1 LAST MATERIAL X6S
J 0
(-1625 4400);
DISPLAY 0.489362 (-1625 4400);
PAINT SKYBLUE (-1625 4400);
FORCEPROP 1 LAST TOLERANCE 20%
J 0
(-1625 4450);
DISPLAY 0.489362 (-1625 4450);
PAINT SKYBLUE (-1625 4450);
FORCEPROP 1 LAST VALUE 22UF
J 0
(-1625 4550);
DISPLAY 0.489362 (-1625 4550);
PAINT SKYBLUE (-1625 4550);
FORCEPROP 1 LAST PART_NUMBER CH622KMEB02
J 0
(-1625 4350);
DISPLAY 0.489362 (-1625 4350);
PAINT SKYBLUE (-1625 4350);
FORCEPROP 1 LAST VOLTAGE 4V
J 0
(-1625 4500);
DISPLAY 0.489362 (-1625 4500);
PAINT SKYBLUE (-1625 4500);
FORCEPROP 1 LAST PACK_TYPE C0402
J 0
(-1625 4300);
DISPLAY 0.489362 (-1625 4300);
PAINT SKYBLUE (-1625 4300);
FORCEPROP 2 LAST CDS_LIB pure_quanta
J 0
(-1675 4500);
PAINT MONO (-1675 4500);
DISPLAY INVISIBLE (-1675 4500);
FORCEPROP 1 LAST PATH I106
J 0
(-1625 4650);
DISPLAY 0.978723 (-1625 4650);
PAINT WHITE (-1625 4650);
DISPLAY INVISIBLE (-1625 4650);
FORCEADD Q_CAP..1
(-1225 4500);
FORCEPROP 1 LAST LOCATION C2397
J 0
(-1175 4600);
DISPLAY 0.489362 (-1175 4600);
PAINT SKYBLUE (-1175 4600);
FORCEPROP 2 LAST $SEC 1
J 0
(-1175 4700);
DISPLAY 0.680851 (-1175 4700);
PAINT MONO (-1175 4700);
DISPLAY INVISIBLE (-1175 4700);
FORCEPROP 2 LAST CDS_SEC 1
J 0
(-1175 4700);
DISPLAY 1.021277 (-1175 4700);
DISPLAY INVISIBLE (-1175 4700);
FORCEPROP 1 LASTPIN (-1225 4600) $PN 1
J 0
(-1215 4580);
DISPLAY 0.489362 (-1215 4580);
FORCEPROP 1 LASTPIN (-1225 4400) $PN 2
J 0
(-1215 4380);
DISPLAY 0.489362 (-1215 4380);
FORCEPROP 1 LAST MATERIAL X6S
J 0
(-1175 4400);
DISPLAY 0.489362 (-1175 4400);
PAINT SKYBLUE (-1175 4400);
FORCEPROP 1 LAST TOLERANCE 20%
J 0
(-1175 4450);
DISPLAY 0.489362 (-1175 4450);
PAINT SKYBLUE (-1175 4450);
FORCEPROP 1 LAST VALUE 22UF
J 0
(-1175 4550);
DISPLAY 0.489362 (-1175 4550);
PAINT SKYBLUE (-1175 4550);
FORCEPROP 1 LAST PART_NUMBER CH622KMEB02
J 0
(-1175 4350);
DISPLAY 0.489362 (-1175 4350);
PAINT SKYBLUE (-1175 4350);
FORCEPROP 1 LAST VOLTAGE 4V
J 0
(-1175 4500);
DISPLAY 0.489362 (-1175 4500);
PAINT SKYBLUE (-1175 4500);
FORCEPROP 1 LAST PACK_TYPE C0402
J 0
(-1175 4300);
DISPLAY 0.489362 (-1175 4300);
PAINT SKYBLUE (-1175 4300);
FORCEPROP 2 LAST CDS_LIB pure_quanta
J 0
(-1225 4500);
PAINT MONO (-1225 4500);
DISPLAY INVISIBLE (-1225 4500);
FORCEPROP 1 LAST PATH I107
J 0
(-1175 4650);
DISPLAY 0.978723 (-1175 4650);
PAINT WHITE (-1175 4650);
DISPLAY INVISIBLE (-1175 4650);
FORCEADD UNIVERSAL_GND..1
(-825 4125);
FORCEPROP 3 LASTPIN (-825 4175) SIG_NAME GND\g
J 0
(-815 4185);
DISPLAY 0.659574 (-815 4185);
PAINT MONO (-815 4185);
DISPLAY INVISIBLE (-815 4185);
FORCEPROP 2 LAST CDS_LIB pure_quanta_power
J 0
(-825 4125);
PAINT MONO (-825 4125);
DISPLAY INVISIBLE (-825 4125);
FORCEPROP 1 LAST PATH I108
J 0
(-750 4125);
DISPLAY 0.872340 (-750 4125);
PAINT AQUA (-750 4125);
DISPLAY INVISIBLE (-750 4125);
FORCEPROP 1 LAST HDL_POWER GND
J 1
(-800 4050);
DISPLAY 0.872340 (-800 4050);
PAINT GREEN (-800 4050);
DISPLAY INVISIBLE (-800 4050);
FORCEADD Q_CAP..1
(-825 4500);
FORCEPROP 1 LAST LOCATION C2402
J 0
(-775 4600);
DISPLAY 0.489362 (-775 4600);
PAINT SKYBLUE (-775 4600);
FORCEPROP 2 LAST $SEC 1
J 0
(-775 4700);
DISPLAY 0.680851 (-775 4700);
PAINT MONO (-775 4700);
DISPLAY INVISIBLE (-775 4700);
FORCEPROP 2 LAST CDS_SEC 1
J 0
(-775 4700);
DISPLAY 1.021277 (-775 4700);
DISPLAY INVISIBLE (-775 4700);
FORCEPROP 1 LASTPIN (-825 4600) $PN 1
J 0
(-815 4580);
DISPLAY 0.489362 (-815 4580);
FORCEPROP 1 LASTPIN (-825 4400) $PN 2
J 0
(-815 4380);
DISPLAY 0.489362 (-815 4380);
FORCEPROP 1 LAST MATERIAL X6S
J 0
(-775 4400);
DISPLAY 0.489362 (-775 4400);
PAINT SKYBLUE (-775 4400);
FORCEPROP 1 LAST TOLERANCE 20%
J 0
(-775 4450);
DISPLAY 0.489362 (-775 4450);
PAINT SKYBLUE (-775 4450);
FORCEPROP 1 LAST VALUE 22UF
J 0
(-775 4550);
DISPLAY 0.489362 (-775 4550);
PAINT SKYBLUE (-775 4550);
FORCEPROP 1 LAST PART_NUMBER CH622KMEB02
J 0
(-775 4350);
DISPLAY 0.489362 (-775 4350);
PAINT SKYBLUE (-775 4350);
FORCEPROP 1 LAST VOLTAGE 4V
J 0
(-775 4500);
DISPLAY 0.489362 (-775 4500);
PAINT SKYBLUE (-775 4500);
FORCEPROP 1 LAST PACK_TYPE C0402
J 0
(-775 4300);
DISPLAY 0.489362 (-775 4300);
PAINT SKYBLUE (-775 4300);
FORCEPROP 2 LAST CDS_LIB pure_quanta
J 0
(-825 4500);
PAINT MONO (-825 4500);
DISPLAY INVISIBLE (-825 4500);
FORCEPROP 1 LAST PATH I109
J 0
(-775 4650);
DISPLAY 0.978723 (-775 4650);
PAINT WHITE (-775 4650);
DISPLAY INVISIBLE (-775 4650);
FORCEADD Q_CAP..1
(-8500 2125);
FORCEPROP 1 LAST LOCATION C2309
J 0
(-8450 2225);
DISPLAY 0.489362 (-8450 2225);
PAINT SKYBLUE (-8450 2225);
FORCEPROP 2 LAST $SEC 1
J 0
(-8450 2325);
DISPLAY 0.680851 (-8450 2325);
PAINT MONO (-8450 2325);
DISPLAY INVISIBLE (-8450 2325);
FORCEPROP 2 LAST CDS_SEC 1
J 0
(-8450 2325);
DISPLAY 1.021277 (-8450 2325);
DISPLAY INVISIBLE (-8450 2325);
FORCEPROP 1 LASTPIN (-8500 2225) $PN 1
J 0
(-8490 2205);
DISPLAY 0.489362 (-8490 2205);
FORCEPROP 1 LASTPIN (-8500 2025) $PN 2
J 0
(-8490 2005);
DISPLAY 0.489362 (-8490 2005);
FORCEPROP 1 LAST MATERIAL X6S
J 0
(-8450 2025);
DISPLAY 0.489362 (-8450 2025);
PAINT SKYBLUE (-8450 2025);
FORCEPROP 1 LAST TOLERANCE 20%
J 0
(-8450 2075);
DISPLAY 0.489362 (-8450 2075);
PAINT SKYBLUE (-8450 2075);
FORCEPROP 1 LAST VALUE 22UF
J 0
(-8450 2175);
DISPLAY 0.489362 (-8450 2175);
PAINT SKYBLUE (-8450 2175);
FORCEPROP 1 LAST PART_NUMBER CH622KMEB02
J 0
(-8450 1975);
DISPLAY 0.489362 (-8450 1975);
PAINT SKYBLUE (-8450 1975);
FORCEPROP 1 LAST VOLTAGE 4V
J 0
(-8450 2125);
DISPLAY 0.489362 (-8450 2125);
PAINT SKYBLUE (-8450 2125);
FORCEPROP 1 LAST PACK_TYPE C0402
J 0
(-8450 1925);
DISPLAY 0.489362 (-8450 1925);
PAINT SKYBLUE (-8450 1925);
FORCEPROP 2 LAST CDS_LIB pure_quanta
J 0
(-8500 2125);
PAINT MONO (-8500 2125);
DISPLAY INVISIBLE (-8500 2125);
FORCEPROP 1 LAST PATH I11
J 0
(-8450 2275);
DISPLAY 0.978723 (-8450 2275);
PAINT WHITE (-8450 2275);
DISPLAY INVISIBLE (-8450 2275);
FORCEADD Q_CAP..1
(-4825 4500);
FORCEPROP 1 LAST LOCATION C2350
J 0
(-4775 4600);
DISPLAY 0.489362 (-4775 4600);
PAINT SKYBLUE (-4775 4600);
FORCEPROP 2 LAST $SEC 1
J 0
(-4775 4700);
DISPLAY 0.680851 (-4775 4700);
PAINT MONO (-4775 4700);
DISPLAY INVISIBLE (-4775 4700);
FORCEPROP 2 LAST CDS_SEC 1
J 0
(-4775 4700);
DISPLAY 1.021277 (-4775 4700);
DISPLAY INVISIBLE (-4775 4700);
FORCEPROP 1 LASTPIN (-4825 4600) $PN 1
J 0
(-4815 4580);
DISPLAY 0.489362 (-4815 4580);
FORCEPROP 1 LASTPIN (-4825 4400) $PN 2
J 0
(-4815 4380);
DISPLAY 0.489362 (-4815 4380);
FORCEPROP 1 LAST MATERIAL X6S
J 0
(-4775 4400);
DISPLAY 0.489362 (-4775 4400);
PAINT SKYBLUE (-4775 4400);
FORCEPROP 1 LAST TOLERANCE 20%
J 0
(-4775 4450);
DISPLAY 0.489362 (-4775 4450);
PAINT SKYBLUE (-4775 4450);
FORCEPROP 1 LAST VALUE 22UF
J 0
(-4775 4550);
DISPLAY 0.489362 (-4775 4550);
PAINT SKYBLUE (-4775 4550);
FORCEPROP 1 LAST PART_NUMBER CH622KMEB02
J 0
(-4775 4350);
DISPLAY 0.489362 (-4775 4350);
PAINT SKYBLUE (-4775 4350);
FORCEPROP 1 LAST VOLTAGE 4V
J 0
(-4775 4500);
DISPLAY 0.489362 (-4775 4500);
PAINT SKYBLUE (-4775 4500);
FORCEPROP 1 LAST PACK_TYPE C0402
J 0
(-4775 4300);
DISPLAY 0.489362 (-4775 4300);
PAINT SKYBLUE (-4775 4300);
FORCEPROP 2 LAST CDS_LIB pure_quanta
J 0
(-4825 4500);
PAINT MONO (-4825 4500);
DISPLAY INVISIBLE (-4825 4500);
FORCEPROP 1 LAST PATH I110
J 0
(-4775 4650);
DISPLAY 0.978723 (-4775 4650);
PAINT WHITE (-4775 4650);
DISPLAY INVISIBLE (-4775 4650);
FORCEADD Q_CAP..1
(-8950 2925);
FORCEPROP 1 LAST LOCATION C2302
J 0
(-8900 3025);
DISPLAY 0.489362 (-8900 3025);
PAINT SKYBLUE (-8900 3025);
FORCEPROP 2 LAST $SEC 1
J 0
(-8900 3125);
DISPLAY 0.680851 (-8900 3125);
PAINT MONO (-8900 3125);
DISPLAY INVISIBLE (-8900 3125);
FORCEPROP 2 LAST CDS_SEC 1
J 0
(-8900 3125);
DISPLAY 1.021277 (-8900 3125);
DISPLAY INVISIBLE (-8900 3125);
FORCEPROP 1 LASTPIN (-8950 3025) $PN 1
J 0
(-8940 3005);
DISPLAY 0.489362 (-8940 3005);
FORCEPROP 1 LASTPIN (-8950 2825) $PN 2
J 0
(-8940 2805);
DISPLAY 0.489362 (-8940 2805);
FORCEPROP 1 LAST MATERIAL X6S
J 0
(-8900 2825);
DISPLAY 0.489362 (-8900 2825);
PAINT SKYBLUE (-8900 2825);
FORCEPROP 1 LAST TOLERANCE 20%
J 0
(-8900 2875);
DISPLAY 0.489362 (-8900 2875);
PAINT SKYBLUE (-8900 2875);
FORCEPROP 1 LAST VALUE 22UF
J 0
(-8900 2975);
DISPLAY 0.489362 (-8900 2975);
PAINT SKYBLUE (-8900 2975);
FORCEPROP 1 LAST PART_NUMBER CH622KMEB02
J 0
(-8900 2775);
DISPLAY 0.489362 (-8900 2775);
PAINT SKYBLUE (-8900 2775);
FORCEPROP 1 LAST VOLTAGE 4V
J 0
(-8900 2925);
DISPLAY 0.489362 (-8900 2925);
PAINT SKYBLUE (-8900 2925);
FORCEPROP 1 LAST PACK_TYPE C0402
J 0
(-8900 2725);
DISPLAY 0.489362 (-8900 2725);
PAINT SKYBLUE (-8900 2725);
FORCEPROP 2 LAST CDS_LIB pure_quanta
J 0
(-8950 2925);
PAINT MONO (-8950 2925);
DISPLAY INVISIBLE (-8950 2925);
FORCEPROP 1 LAST PATH I12
J 0
(-8900 3075);
DISPLAY 0.978723 (-8900 3075);
PAINT WHITE (-8900 3075);
DISPLAY INVISIBLE (-8900 3075);
FORCEADD Q_CAP..1
(-8950 3725);
FORCEPROP 1 LAST LOCATION C2301
J 0
(-8900 3825);
DISPLAY 0.489362 (-8900 3825);
PAINT SKYBLUE (-8900 3825);
FORCEPROP 2 LAST $SEC 1
J 0
(-8900 3925);
DISPLAY 0.680851 (-8900 3925);
PAINT MONO (-8900 3925);
DISPLAY INVISIBLE (-8900 3925);
FORCEPROP 2 LAST CDS_SEC 1
J 0
(-8900 3925);
DISPLAY 1.021277 (-8900 3925);
DISPLAY INVISIBLE (-8900 3925);
FORCEPROP 1 LASTPIN (-8950 3825) $PN 1
J 0
(-8940 3805);
DISPLAY 0.489362 (-8940 3805);
FORCEPROP 1 LASTPIN (-8950 3625) $PN 2
J 0
(-8940 3605);
DISPLAY 0.489362 (-8940 3605);
FORCEPROP 1 LAST MATERIAL X6S
J 0
(-8900 3625);
DISPLAY 0.489362 (-8900 3625);
PAINT SKYBLUE (-8900 3625);
FORCEPROP 1 LAST TOLERANCE 20%
J 0
(-8900 3675);
DISPLAY 0.489362 (-8900 3675);
PAINT SKYBLUE (-8900 3675);
FORCEPROP 1 LAST VALUE 22UF
J 0
(-8900 3775);
DISPLAY 0.489362 (-8900 3775);
PAINT SKYBLUE (-8900 3775);
FORCEPROP 1 LAST PART_NUMBER CH622KMEB02
J 0
(-8900 3575);
DISPLAY 0.489362 (-8900 3575);
PAINT SKYBLUE (-8900 3575);
FORCEPROP 1 LAST VOLTAGE 4V
J 0
(-8900 3725);
DISPLAY 0.489362 (-8900 3725);
PAINT SKYBLUE (-8900 3725);
FORCEPROP 1 LAST PACK_TYPE C0402
J 0
(-8900 3525);
DISPLAY 0.489362 (-8900 3525);
PAINT SKYBLUE (-8900 3525);
FORCEPROP 2 LAST CDS_LIB pure_quanta
J 0
(-8950 3725);
PAINT MONO (-8950 3725);
DISPLAY INVISIBLE (-8950 3725);
FORCEPROP 1 LAST PATH I13
J 0
(-8900 3875);
DISPLAY 0.978723 (-8900 3875);
PAINT WHITE (-8900 3875);
DISPLAY INVISIBLE (-8900 3875);
FORCEADD Q_CAP..1
(-8500 2925);
FORCEPROP 1 LAST LOCATION C2308
J 0
(-8450 3025);
DISPLAY 0.489362 (-8450 3025);
PAINT SKYBLUE (-8450 3025);
FORCEPROP 2 LAST $SEC 1
J 0
(-8450 3125);
DISPLAY 0.680851 (-8450 3125);
PAINT MONO (-8450 3125);
DISPLAY INVISIBLE (-8450 3125);
FORCEPROP 2 LAST CDS_SEC 1
J 0
(-8450 3125);
DISPLAY 1.021277 (-8450 3125);
DISPLAY INVISIBLE (-8450 3125);
FORCEPROP 1 LASTPIN (-8500 3025) $PN 1
J 0
(-8490 3005);
DISPLAY 0.489362 (-8490 3005);
FORCEPROP 1 LASTPIN (-8500 2825) $PN 2
J 0
(-8490 2805);
DISPLAY 0.489362 (-8490 2805);
FORCEPROP 1 LAST MATERIAL X6S
J 0
(-8450 2825);
DISPLAY 0.489362 (-8450 2825);
PAINT SKYBLUE (-8450 2825);
FORCEPROP 1 LAST TOLERANCE 20%
J 0
(-8450 2875);
DISPLAY 0.489362 (-8450 2875);
PAINT SKYBLUE (-8450 2875);
FORCEPROP 1 LAST VALUE 22UF
J 0
(-8450 2975);
DISPLAY 0.489362 (-8450 2975);
PAINT SKYBLUE (-8450 2975);
FORCEPROP 1 LAST PART_NUMBER CH622KMEB02
J 0
(-8450 2775);
DISPLAY 0.489362 (-8450 2775);
PAINT SKYBLUE (-8450 2775);
FORCEPROP 1 LAST VOLTAGE 4V
J 0
(-8450 2925);
DISPLAY 0.489362 (-8450 2925);
PAINT SKYBLUE (-8450 2925);
FORCEPROP 1 LAST PACK_TYPE C0402
J 0
(-8450 2725);
DISPLAY 0.489362 (-8450 2725);
PAINT SKYBLUE (-8450 2725);
FORCEPROP 2 LAST CDS_LIB pure_quanta
J 0
(-8500 2925);
PAINT MONO (-8500 2925);
DISPLAY INVISIBLE (-8500 2925);
FORCEPROP 1 LAST PATH I14
J 0
(-8450 3075);
DISPLAY 0.978723 (-8450 3075);
PAINT WHITE (-8450 3075);
DISPLAY INVISIBLE (-8450 3075);
FORCEADD Q_CAP..1
(-8500 3725);
FORCEPROP 1 LAST LOCATION C2307
J 0
(-8450 3825);
DISPLAY 0.489362 (-8450 3825);
PAINT SKYBLUE (-8450 3825);
FORCEPROP 2 LAST $SEC 1
J 0
(-8450 3925);
DISPLAY 0.680851 (-8450 3925);
PAINT MONO (-8450 3925);
DISPLAY INVISIBLE (-8450 3925);
FORCEPROP 2 LAST CDS_SEC 1
J 0
(-8450 3925);
DISPLAY 1.021277 (-8450 3925);
DISPLAY INVISIBLE (-8450 3925);
FORCEPROP 1 LASTPIN (-8500 3825) $PN 1
J 0
(-8490 3805);
DISPLAY 0.489362 (-8490 3805);
FORCEPROP 1 LASTPIN (-8500 3625) $PN 2
J 0
(-8490 3605);
DISPLAY 0.489362 (-8490 3605);
FORCEPROP 1 LAST MATERIAL X6S
J 0
(-8450 3625);
DISPLAY 0.489362 (-8450 3625);
PAINT SKYBLUE (-8450 3625);
FORCEPROP 1 LAST TOLERANCE 20%
J 0
(-8450 3675);
DISPLAY 0.489362 (-8450 3675);
PAINT SKYBLUE (-8450 3675);
FORCEPROP 1 LAST VALUE 22UF
J 0
(-8450 3775);
DISPLAY 0.489362 (-8450 3775);
PAINT SKYBLUE (-8450 3775);
FORCEPROP 1 LAST PART_NUMBER CH622KMEB02
J 0
(-8450 3575);
DISPLAY 0.489362 (-8450 3575);
PAINT SKYBLUE (-8450 3575);
FORCEPROP 1 LAST VOLTAGE 4V
J 0
(-8450 3725);
DISPLAY 0.489362 (-8450 3725);
PAINT SKYBLUE (-8450 3725);
FORCEPROP 1 LAST PACK_TYPE C0402
J 0
(-8450 3525);
DISPLAY 0.489362 (-8450 3525);
PAINT SKYBLUE (-8450 3525);
FORCEPROP 2 LAST CDS_LIB pure_quanta
J 0
(-8500 3725);
PAINT MONO (-8500 3725);
DISPLAY INVISIBLE (-8500 3725);
FORCEPROP 1 LAST PATH I15
J 0
(-8450 3875);
DISPLAY 0.978723 (-8450 3875);
PAINT WHITE (-8450 3875);
DISPLAY INVISIBLE (-8450 3875);
FORCEADD UNIVERSAL_POWER..1
(-9400 4000);
FORCEPROP 3 LASTPIN (-9400 3950) SIG_NAME PVDDCR_CPU0_P1\g
J 0
(-9390 3960);
DISPLAY 0.659574 (-9390 3960);
PAINT MONO (-9390 3960);
DISPLAY INVISIBLE (-9390 3960);
FORCEPROP 1 LAST HDL_POWER PVDDCR_CPU0_P1
J 1
(-9400 4050);
DISPLAY 0.489362 (-9400 4050);
PAINT GREEN (-9400 4050);
FORCEPROP 2 LAST CDS_LIB pure_quanta_power
J 0
(-9400 4000);
DISPLAY INVISIBLE (-9400 4000);
FORCEPROP 1 LAST PATH I16
J 0
(-9350 4025);
DISPLAY 0.872340 (-9350 4025);
PAINT AQUA (-9350 4025);
DISPLAY INVISIBLE (-9350 4025);
FORCEADD Q_CAP..1
(-9400 4500);
FORCEPROP 1 LAST LOCATION C2294
J 0
(-9350 4600);
DISPLAY 0.489362 (-9350 4600);
PAINT SKYBLUE (-9350 4600);
FORCEPROP 2 LAST $SEC 1
J 0
(-9350 4700);
DISPLAY 0.680851 (-9350 4700);
PAINT MONO (-9350 4700);
DISPLAY INVISIBLE (-9350 4700);
FORCEPROP 2 LAST CDS_SEC 1
J 0
(-9350 4700);
DISPLAY 1.021277 (-9350 4700);
DISPLAY INVISIBLE (-9350 4700);
FORCEPROP 1 LASTPIN (-9400 4600) $PN 1
J 0
(-9390 4580);
DISPLAY 0.489362 (-9390 4580);
FORCEPROP 1 LASTPIN (-9400 4400) $PN 2
J 0
(-9390 4380);
DISPLAY 0.489362 (-9390 4380);
FORCEPROP 1 LAST MATERIAL X6S
J 0
(-9350 4400);
DISPLAY 0.489362 (-9350 4400);
PAINT SKYBLUE (-9350 4400);
FORCEPROP 1 LAST TOLERANCE 20%
J 0
(-9350 4450);
DISPLAY 0.489362 (-9350 4450);
PAINT SKYBLUE (-9350 4450);
FORCEPROP 1 LAST VALUE 22UF
J 0
(-9350 4550);
DISPLAY 0.489362 (-9350 4550);
PAINT SKYBLUE (-9350 4550);
FORCEPROP 1 LAST PART_NUMBER CH622KMEB02
J 0
(-9350 4350);
DISPLAY 0.489362 (-9350 4350);
PAINT SKYBLUE (-9350 4350);
FORCEPROP 1 LAST VOLTAGE 4V
J 0
(-9350 4500);
DISPLAY 0.489362 (-9350 4500);
PAINT SKYBLUE (-9350 4500);
FORCEPROP 1 LAST PACK_TYPE C0402
J 0
(-9350 4300);
DISPLAY 0.489362 (-9350 4300);
PAINT SKYBLUE (-9350 4300);
FORCEPROP 2 LAST CDS_LIB pure_quanta
J 0
(-9400 4500);
PAINT MONO (-9400 4500);
DISPLAY INVISIBLE (-9400 4500);
FORCEPROP 1 LAST PATH I17
J 0
(-9350 4650);
DISPLAY 0.978723 (-9350 4650);
PAINT WHITE (-9350 4650);
DISPLAY INVISIBLE (-9350 4650);
FORCEADD UNIVERSAL_POWER..1
(-9400 4775);
FORCEPROP 3 LASTPIN (-9400 4725) SIG_NAME PVDDCR_CPU0_P1\g
J 0
(-9390 4735);
DISPLAY 0.659574 (-9390 4735);
PAINT MONO (-9390 4735);
DISPLAY INVISIBLE (-9390 4735);
FORCEPROP 1 LAST HDL_POWER PVDDCR_CPU0_P1
J 1
(-9400 4825);
DISPLAY 0.489362 (-9400 4825);
PAINT GREEN (-9400 4825);
FORCEPROP 2 LAST CDS_LIB pure_quanta_power
J 0
(-9400 4775);
DISPLAY INVISIBLE (-9400 4775);
FORCEPROP 1 LAST PATH I18
J 0
(-9350 4800);
DISPLAY 0.872340 (-9350 4800);
PAINT AQUA (-9350 4800);
DISPLAY INVISIBLE (-9350 4800);
FORCEADD Q_CAP..1
(-8950 4500);
FORCEPROP 1 LAST LOCATION C2300
J 0
(-8900 4600);
DISPLAY 0.489362 (-8900 4600);
PAINT SKYBLUE (-8900 4600);
FORCEPROP 2 LAST $SEC 1
J 0
(-8900 4700);
DISPLAY 0.680851 (-8900 4700);
PAINT MONO (-8900 4700);
DISPLAY INVISIBLE (-8900 4700);
FORCEPROP 2 LAST CDS_SEC 1
J 0
(-8900 4700);
DISPLAY 1.021277 (-8900 4700);
DISPLAY INVISIBLE (-8900 4700);
FORCEPROP 1 LASTPIN (-8950 4600) $PN 1
J 0
(-8940 4580);
DISPLAY 0.489362 (-8940 4580);
FORCEPROP 1 LASTPIN (-8950 4400) $PN 2
J 0
(-8940 4380);
DISPLAY 0.489362 (-8940 4380);
FORCEPROP 1 LAST MATERIAL X6S
J 0
(-8900 4400);
DISPLAY 0.489362 (-8900 4400);
PAINT SKYBLUE (-8900 4400);
FORCEPROP 1 LAST TOLERANCE 20%
J 0
(-8900 4450);
DISPLAY 0.489362 (-8900 4450);
PAINT SKYBLUE (-8900 4450);
FORCEPROP 1 LAST VALUE 22UF
J 0
(-8900 4550);
DISPLAY 0.489362 (-8900 4550);
PAINT SKYBLUE (-8900 4550);
FORCEPROP 1 LAST PART_NUMBER CH622KMEB02
J 0
(-8900 4350);
DISPLAY 0.489362 (-8900 4350);
PAINT SKYBLUE (-8900 4350);
FORCEPROP 1 LAST VOLTAGE 4V
J 0
(-8900 4500);
DISPLAY 0.489362 (-8900 4500);
PAINT SKYBLUE (-8900 4500);
FORCEPROP 1 LAST PACK_TYPE C0402
J 0
(-8900 4300);
DISPLAY 0.489362 (-8900 4300);
PAINT SKYBLUE (-8900 4300);
FORCEPROP 2 LAST CDS_LIB pure_quanta
J 0
(-8950 4500);
PAINT MONO (-8950 4500);
DISPLAY INVISIBLE (-8950 4500);
FORCEPROP 1 LAST PATH I19
J 0
(-8900 4650);
DISPLAY 0.978723 (-8900 4650);
PAINT WHITE (-8900 4650);
DISPLAY INVISIBLE (-8900 4650);
FORCEADD UNIVERSAL_POWER..1
(-9400 1600);
FORCEPROP 3 LASTPIN (-9400 1550) SIG_NAME PVDDCR_CPU0_P1\g
J 0
(-9390 1560);
DISPLAY 0.659574 (-9390 1560);
PAINT MONO (-9390 1560);
DISPLAY INVISIBLE (-9390 1560);
FORCEPROP 1 LAST HDL_POWER PVDDCR_CPU0_P1
J 1
(-9400 1650);
DISPLAY 0.489362 (-9400 1650);
PAINT GREEN (-9400 1650);
FORCEPROP 2 LAST CDS_LIB pure_quanta_power
J 0
(-9400 1600);
DISPLAY INVISIBLE (-9400 1600);
FORCEPROP 1 LAST PATH I2
J 0
(-9350 1625);
DISPLAY 0.872340 (-9350 1625);
PAINT AQUA (-9350 1625);
DISPLAY INVISIBLE (-9350 1625);
FORCEADD Q_CAP..1
(-8500 4500);
FORCEPROP 1 LAST LOCATION C2306
J 0
(-8450 4600);
DISPLAY 0.489362 (-8450 4600);
PAINT SKYBLUE (-8450 4600);
FORCEPROP 2 LAST $SEC 1
J 0
(-8450 4700);
DISPLAY 0.680851 (-8450 4700);
PAINT MONO (-8450 4700);
DISPLAY INVISIBLE (-8450 4700);
FORCEPROP 2 LAST CDS_SEC 1
J 0
(-8450 4700);
DISPLAY 1.021277 (-8450 4700);
DISPLAY INVISIBLE (-8450 4700);
FORCEPROP 1 LASTPIN (-8500 4600) $PN 1
J 0
(-8490 4580);
DISPLAY 0.489362 (-8490 4580);
FORCEPROP 1 LASTPIN (-8500 4400) $PN 2
J 0
(-8490 4380);
DISPLAY 0.489362 (-8490 4380);
FORCEPROP 1 LAST MATERIAL X6S
J 0
(-8450 4400);
DISPLAY 0.489362 (-8450 4400);
PAINT SKYBLUE (-8450 4400);
FORCEPROP 1 LAST TOLERANCE 20%
J 0
(-8450 4450);
DISPLAY 0.489362 (-8450 4450);
PAINT SKYBLUE (-8450 4450);
FORCEPROP 1 LAST VALUE 22UF
J 0
(-8450 4550);
DISPLAY 0.489362 (-8450 4550);
PAINT SKYBLUE (-8450 4550);
FORCEPROP 1 LAST PART_NUMBER CH622KMEB02
J 0
(-8450 4350);
DISPLAY 0.489362 (-8450 4350);
PAINT SKYBLUE (-8450 4350);
FORCEPROP 1 LAST VOLTAGE 4V
J 0
(-8450 4500);
DISPLAY 0.489362 (-8450 4500);
PAINT SKYBLUE (-8450 4500);
FORCEPROP 1 LAST PACK_TYPE C0402
J 0
(-8450 4300);
DISPLAY 0.489362 (-8450 4300);
PAINT SKYBLUE (-8450 4300);
FORCEPROP 2 LAST CDS_LIB pure_quanta
J 0
(-8500 4500);
PAINT MONO (-8500 4500);
DISPLAY INVISIBLE (-8500 4500);
FORCEPROP 1 LAST PATH I20
J 0
(-8450 4650);
DISPLAY 0.978723 (-8450 4650);
PAINT WHITE (-8450 4650);
DISPLAY INVISIBLE (-8450 4650);
FORCEADD Q_CAP..1
(-8050 1325);
FORCEPROP 1 LAST LOCATION C2316
J 0
(-8000 1425);
DISPLAY 0.489362 (-8000 1425);
PAINT SKYBLUE (-8000 1425);
FORCEPROP 2 LAST $SEC 1
J 0
(-8000 1525);
DISPLAY 0.680851 (-8000 1525);
PAINT MONO (-8000 1525);
DISPLAY INVISIBLE (-8000 1525);
FORCEPROP 2 LAST CDS_SEC 1
J 0
(-8000 1525);
DISPLAY 1.021277 (-8000 1525);
DISPLAY INVISIBLE (-8000 1525);
FORCEPROP 1 LASTPIN (-8050 1425) $PN 1
J 0
(-8040 1405);
DISPLAY 0.489362 (-8040 1405);
FORCEPROP 1 LASTPIN (-8050 1225) $PN 2
J 0
(-8040 1205);
DISPLAY 0.489362 (-8040 1205);
FORCEPROP 1 LAST MATERIAL X6S
J 0
(-8000 1225);
DISPLAY 0.489362 (-8000 1225);
PAINT SKYBLUE (-8000 1225);
FORCEPROP 1 LAST TOLERANCE 20%
J 0
(-8000 1275);
DISPLAY 0.489362 (-8000 1275);
PAINT SKYBLUE (-8000 1275);
FORCEPROP 1 LAST VALUE 22UF
J 0
(-8000 1375);
DISPLAY 0.489362 (-8000 1375);
PAINT SKYBLUE (-8000 1375);
FORCEPROP 1 LAST PART_NUMBER CH622KMEB02
J 0
(-8000 1175);
DISPLAY 0.489362 (-8000 1175);
PAINT SKYBLUE (-8000 1175);
FORCEPROP 1 LAST VOLTAGE 4V
J 0
(-8000 1325);
DISPLAY 0.489362 (-8000 1325);
PAINT SKYBLUE (-8000 1325);
FORCEPROP 1 LAST PACK_TYPE C0402
J 0
(-8000 1125);
DISPLAY 0.489362 (-8000 1125);
PAINT SKYBLUE (-8000 1125);
FORCEPROP 2 LAST CDS_LIB pure_quanta
J 0
(-8050 1325);
PAINT MONO (-8050 1325);
DISPLAY INVISIBLE (-8050 1325);
FORCEPROP 1 LAST PATH I21
J 0
(-8000 1475);
DISPLAY 0.978723 (-8000 1475);
PAINT WHITE (-8000 1475);
DISPLAY INVISIBLE (-8000 1475);
FORCEADD UNIVERSAL_GND..1
(-7600 950);
FORCEPROP 3 LASTPIN (-7600 1000) SIG_NAME GND\g
J 0
(-7590 1010);
DISPLAY 0.659574 (-7590 1010);
PAINT MONO (-7590 1010);
DISPLAY INVISIBLE (-7590 1010);
FORCEPROP 2 LAST CDS_LIB pure_quanta_power
J 0
(-7600 950);
DISPLAY INVISIBLE (-7600 950);
FORCEPROP 1 LAST PATH I22
J 0
(-7525 950);
DISPLAY 0.872340 (-7525 950);
PAINT AQUA (-7525 950);
DISPLAY INVISIBLE (-7525 950);
FORCEPROP 1 LAST HDL_POWER GND
J 1
(-7575 875);
DISPLAY 0.872340 (-7575 875);
PAINT GREEN (-7575 875);
DISPLAY INVISIBLE (-7575 875);
FORCEADD Q_CAP..1
(-7600 1325);
FORCEPROP 1 LAST LOCATION C2322
J 0
(-7550 1425);
DISPLAY 0.489362 (-7550 1425);
PAINT SKYBLUE (-7550 1425);
FORCEPROP 2 LAST $SEC 1
J 0
(-7550 1525);
DISPLAY 0.680851 (-7550 1525);
PAINT MONO (-7550 1525);
DISPLAY INVISIBLE (-7550 1525);
FORCEPROP 2 LAST CDS_SEC 1
J 0
(-7550 1525);
DISPLAY 1.021277 (-7550 1525);
DISPLAY INVISIBLE (-7550 1525);
FORCEPROP 1 LASTPIN (-7600 1425) $PN 1
J 0
(-7590 1405);
DISPLAY 0.489362 (-7590 1405);
FORCEPROP 1 LASTPIN (-7600 1225) $PN 2
J 0
(-7590 1205);
DISPLAY 0.489362 (-7590 1205);
FORCEPROP 1 LAST MATERIAL X6S
J 0
(-7550 1225);
DISPLAY 0.489362 (-7550 1225);
PAINT SKYBLUE (-7550 1225);
FORCEPROP 1 LAST TOLERANCE 20%
J 0
(-7550 1275);
DISPLAY 0.489362 (-7550 1275);
PAINT SKYBLUE (-7550 1275);
FORCEPROP 1 LAST VALUE 22UF
J 0
(-7550 1375);
DISPLAY 0.489362 (-7550 1375);
PAINT SKYBLUE (-7550 1375);
FORCEPROP 1 LAST PART_NUMBER CH622KMEB02
J 0
(-7550 1175);
DISPLAY 0.489362 (-7550 1175);
PAINT SKYBLUE (-7550 1175);
FORCEPROP 1 LAST VOLTAGE 4V
J 0
(-7550 1325);
DISPLAY 0.489362 (-7550 1325);
PAINT SKYBLUE (-7550 1325);
FORCEPROP 1 LAST PACK_TYPE C0402
J 0
(-7550 1125);
DISPLAY 0.489362 (-7550 1125);
PAINT SKYBLUE (-7550 1125);
FORCEPROP 2 LAST CDS_LIB pure_quanta
J 0
(-7600 1325);
PAINT MONO (-7600 1325);
DISPLAY INVISIBLE (-7600 1325);
FORCEPROP 1 LAST PATH I23
J 0
(-7550 1475);
DISPLAY 0.978723 (-7550 1475);
PAINT WHITE (-7550 1475);
DISPLAY INVISIBLE (-7550 1475);
FORCEADD Q_CAP..1
(-8050 2125);
FORCEPROP 1 LAST LOCATION C2315
J 0
(-8000 2225);
DISPLAY 0.489362 (-8000 2225);
PAINT SKYBLUE (-8000 2225);
FORCEPROP 2 LAST $SEC 1
J 0
(-8000 2325);
DISPLAY 0.680851 (-8000 2325);
PAINT MONO (-8000 2325);
DISPLAY INVISIBLE (-8000 2325);
FORCEPROP 2 LAST CDS_SEC 1
J 0
(-8000 2325);
DISPLAY 1.021277 (-8000 2325);
DISPLAY INVISIBLE (-8000 2325);
FORCEPROP 1 LASTPIN (-8050 2225) $PN 1
J 0
(-8040 2205);
DISPLAY 0.489362 (-8040 2205);
FORCEPROP 1 LASTPIN (-8050 2025) $PN 2
J 0
(-8040 2005);
DISPLAY 0.489362 (-8040 2005);
FORCEPROP 1 LAST MATERIAL X6S
J 0
(-8000 2025);
DISPLAY 0.489362 (-8000 2025);
PAINT SKYBLUE (-8000 2025);
FORCEPROP 1 LAST TOLERANCE 20%
J 0
(-8000 2075);
DISPLAY 0.489362 (-8000 2075);
PAINT SKYBLUE (-8000 2075);
FORCEPROP 1 LAST VALUE 22UF
J 0
(-8000 2175);
DISPLAY 0.489362 (-8000 2175);
PAINT SKYBLUE (-8000 2175);
FORCEPROP 1 LAST PART_NUMBER CH622KMEB02
J 0
(-8000 1975);
DISPLAY 0.489362 (-8000 1975);
PAINT SKYBLUE (-8000 1975);
FORCEPROP 1 LAST VOLTAGE 4V
J 0
(-8000 2125);
DISPLAY 0.489362 (-8000 2125);
PAINT SKYBLUE (-8000 2125);
FORCEPROP 1 LAST PACK_TYPE C0402
J 0
(-8000 1925);
DISPLAY 0.489362 (-8000 1925);
PAINT SKYBLUE (-8000 1925);
FORCEPROP 2 LAST CDS_LIB pure_quanta
J 0
(-8050 2125);
PAINT MONO (-8050 2125);
DISPLAY INVISIBLE (-8050 2125);
FORCEPROP 1 LAST PATH I24
J 0
(-8000 2275);
DISPLAY 0.978723 (-8000 2275);
PAINT WHITE (-8000 2275);
DISPLAY INVISIBLE (-8000 2275);
FORCEADD Q_CAP..1
(-7600 2125);
FORCEPROP 1 LAST LOCATION C2321
J 0
(-7550 2225);
DISPLAY 0.489362 (-7550 2225);
PAINT SKYBLUE (-7550 2225);
FORCEPROP 2 LAST $SEC 1
J 0
(-7550 2325);
DISPLAY 0.680851 (-7550 2325);
PAINT MONO (-7550 2325);
DISPLAY INVISIBLE (-7550 2325);
FORCEPROP 2 LAST CDS_SEC 1
J 0
(-7550 2325);
DISPLAY 1.021277 (-7550 2325);
DISPLAY INVISIBLE (-7550 2325);
FORCEPROP 1 LASTPIN (-7600 2225) $PN 1
J 0
(-7590 2205);
DISPLAY 0.489362 (-7590 2205);
FORCEPROP 1 LASTPIN (-7600 2025) $PN 2
J 0
(-7590 2005);
DISPLAY 0.489362 (-7590 2005);
FORCEPROP 1 LAST MATERIAL X6S
J 0
(-7550 2025);
DISPLAY 0.489362 (-7550 2025);
PAINT SKYBLUE (-7550 2025);
FORCEPROP 1 LAST TOLERANCE 20%
J 0
(-7550 2075);
DISPLAY 0.489362 (-7550 2075);
PAINT SKYBLUE (-7550 2075);
FORCEPROP 1 LAST VALUE 22UF
J 0
(-7550 2175);
DISPLAY 0.489362 (-7550 2175);
PAINT SKYBLUE (-7550 2175);
FORCEPROP 1 LAST PART_NUMBER CH622KMEB02
J 0
(-7550 1975);
DISPLAY 0.489362 (-7550 1975);
PAINT SKYBLUE (-7550 1975);
FORCEPROP 1 LAST VOLTAGE 4V
J 0
(-7550 2125);
DISPLAY 0.489362 (-7550 2125);
PAINT SKYBLUE (-7550 2125);
FORCEPROP 1 LAST PACK_TYPE C0402
J 0
(-7550 1925);
DISPLAY 0.489362 (-7550 1925);
PAINT SKYBLUE (-7550 1925);
FORCEPROP 2 LAST CDS_LIB pure_quanta
J 0
(-7600 2125);
PAINT MONO (-7600 2125);
DISPLAY INVISIBLE (-7600 2125);
FORCEPROP 1 LAST PATH I25
J 0
(-7550 2275);
DISPLAY 0.978723 (-7550 2275);
PAINT WHITE (-7550 2275);
DISPLAY INVISIBLE (-7550 2275);
FORCEADD Q_CAP..1
(-7150 2125);
FORCEPROP 1 LAST LOCATION C2327
J 0
(-7100 2225);
DISPLAY 0.489362 (-7100 2225);
PAINT SKYBLUE (-7100 2225);
FORCEPROP 2 LAST $SEC 1
J 0
(-7100 2325);
DISPLAY 0.680851 (-7100 2325);
PAINT MONO (-7100 2325);
DISPLAY INVISIBLE (-7100 2325);
FORCEPROP 2 LAST CDS_SEC 1
J 0
(-7100 2325);
DISPLAY 1.021277 (-7100 2325);
DISPLAY INVISIBLE (-7100 2325);
FORCEPROP 1 LASTPIN (-7150 2225) $PN 1
J 0
(-7140 2205);
DISPLAY 0.489362 (-7140 2205);
FORCEPROP 1 LASTPIN (-7150 2025) $PN 2
J 0
(-7140 2005);
DISPLAY 0.489362 (-7140 2005);
FORCEPROP 1 LAST MATERIAL X6S
J 0
(-7100 2025);
DISPLAY 0.489362 (-7100 2025);
PAINT SKYBLUE (-7100 2025);
FORCEPROP 1 LAST TOLERANCE 20%
J 0
(-7100 2075);
DISPLAY 0.489362 (-7100 2075);
PAINT SKYBLUE (-7100 2075);
FORCEPROP 1 LAST VALUE 22UF
J 0
(-7100 2175);
DISPLAY 0.489362 (-7100 2175);
PAINT SKYBLUE (-7100 2175);
FORCEPROP 1 LAST PART_NUMBER CH622KMEB02
J 0
(-7100 1975);
DISPLAY 0.489362 (-7100 1975);
PAINT SKYBLUE (-7100 1975);
FORCEPROP 1 LAST VOLTAGE 4V
J 0
(-7100 2125);
DISPLAY 0.489362 (-7100 2125);
PAINT SKYBLUE (-7100 2125);
FORCEPROP 1 LAST PACK_TYPE C0402
J 0
(-7100 1925);
DISPLAY 0.489362 (-7100 1925);
PAINT SKYBLUE (-7100 1925);
FORCEPROP 2 LAST CDS_LIB pure_quanta
J 0
(-7150 2125);
PAINT MONO (-7150 2125);
DISPLAY INVISIBLE (-7150 2125);
FORCEPROP 1 LAST PATH I26
J 0
(-7100 2275);
DISPLAY 0.978723 (-7100 2275);
PAINT WHITE (-7100 2275);
DISPLAY INVISIBLE (-7100 2275);
FORCEADD Q_CAP..1
(-8050 2925);
FORCEPROP 1 LAST LOCATION C2314
J 0
(-8000 3025);
DISPLAY 0.489362 (-8000 3025);
PAINT SKYBLUE (-8000 3025);
FORCEPROP 2 LAST $SEC 1
J 0
(-8000 3125);
DISPLAY 0.680851 (-8000 3125);
PAINT MONO (-8000 3125);
DISPLAY INVISIBLE (-8000 3125);
FORCEPROP 2 LAST CDS_SEC 1
J 0
(-8000 3125);
DISPLAY 1.021277 (-8000 3125);
DISPLAY INVISIBLE (-8000 3125);
FORCEPROP 1 LASTPIN (-8050 3025) $PN 1
J 0
(-8040 3005);
DISPLAY 0.489362 (-8040 3005);
FORCEPROP 1 LASTPIN (-8050 2825) $PN 2
J 0
(-8040 2805);
DISPLAY 0.489362 (-8040 2805);
FORCEPROP 1 LAST MATERIAL X6S
J 0
(-8000 2825);
DISPLAY 0.489362 (-8000 2825);
PAINT SKYBLUE (-8000 2825);
FORCEPROP 1 LAST TOLERANCE 20%
J 0
(-8000 2875);
DISPLAY 0.489362 (-8000 2875);
PAINT SKYBLUE (-8000 2875);
FORCEPROP 1 LAST VALUE 22UF
J 0
(-8000 2975);
DISPLAY 0.489362 (-8000 2975);
PAINT SKYBLUE (-8000 2975);
FORCEPROP 1 LAST PART_NUMBER CH622KMEB02
J 0
(-8000 2775);
DISPLAY 0.489362 (-8000 2775);
PAINT SKYBLUE (-8000 2775);
FORCEPROP 1 LAST VOLTAGE 4V
J 0
(-8000 2925);
DISPLAY 0.489362 (-8000 2925);
PAINT SKYBLUE (-8000 2925);
FORCEPROP 1 LAST PACK_TYPE C0402
J 0
(-8000 2725);
DISPLAY 0.489362 (-8000 2725);
PAINT SKYBLUE (-8000 2725);
FORCEPROP 2 LAST CDS_LIB pure_quanta
J 0
(-8050 2925);
PAINT MONO (-8050 2925);
DISPLAY INVISIBLE (-8050 2925);
FORCEPROP 1 LAST PATH I27
J 0
(-8000 3075);
DISPLAY 0.978723 (-8000 3075);
PAINT WHITE (-8000 3075);
DISPLAY INVISIBLE (-8000 3075);
FORCEADD Q_CAP..1
(-8050 3725);
FORCEPROP 1 LAST LOCATION C2313
J 0
(-8000 3825);
DISPLAY 0.489362 (-8000 3825);
PAINT SKYBLUE (-8000 3825);
FORCEPROP 2 LAST $SEC 1
J 0
(-8000 3925);
DISPLAY 0.680851 (-8000 3925);
PAINT MONO (-8000 3925);
DISPLAY INVISIBLE (-8000 3925);
FORCEPROP 2 LAST CDS_SEC 1
J 0
(-8000 3925);
DISPLAY 1.021277 (-8000 3925);
DISPLAY INVISIBLE (-8000 3925);
FORCEPROP 1 LASTPIN (-8050 3825) $PN 1
J 0
(-8040 3805);
DISPLAY 0.489362 (-8040 3805);
FORCEPROP 1 LASTPIN (-8050 3625) $PN 2
J 0
(-8040 3605);
DISPLAY 0.489362 (-8040 3605);
FORCEPROP 1 LAST MATERIAL X6S
J 0
(-8000 3625);
DISPLAY 0.489362 (-8000 3625);
PAINT SKYBLUE (-8000 3625);
FORCEPROP 1 LAST TOLERANCE 20%
J 0
(-8000 3675);
DISPLAY 0.489362 (-8000 3675);
PAINT SKYBLUE (-8000 3675);
FORCEPROP 1 LAST VALUE 22UF
J 0
(-8000 3775);
DISPLAY 0.489362 (-8000 3775);
PAINT SKYBLUE (-8000 3775);
FORCEPROP 1 LAST PART_NUMBER CH622KMEB02
J 0
(-8000 3575);
DISPLAY 0.489362 (-8000 3575);
PAINT SKYBLUE (-8000 3575);
FORCEPROP 1 LAST VOLTAGE 4V
J 0
(-8000 3725);
DISPLAY 0.489362 (-8000 3725);
PAINT SKYBLUE (-8000 3725);
FORCEPROP 1 LAST PACK_TYPE C0402
J 0
(-8000 3525);
DISPLAY 0.489362 (-8000 3525);
PAINT SKYBLUE (-8000 3525);
FORCEPROP 2 LAST CDS_LIB pure_quanta
J 0
(-8050 3725);
PAINT MONO (-8050 3725);
DISPLAY INVISIBLE (-8050 3725);
FORCEPROP 1 LAST PATH I28
J 0
(-8000 3875);
DISPLAY 0.978723 (-8000 3875);
PAINT WHITE (-8000 3875);
DISPLAY INVISIBLE (-8000 3875);
FORCEADD Q_CAP..1
(-7600 2925);
FORCEPROP 1 LAST LOCATION C2320
J 0
(-7550 3025);
DISPLAY 0.489362 (-7550 3025);
PAINT SKYBLUE (-7550 3025);
FORCEPROP 2 LAST $SEC 1
J 0
(-7550 3125);
DISPLAY 0.680851 (-7550 3125);
PAINT MONO (-7550 3125);
DISPLAY INVISIBLE (-7550 3125);
FORCEPROP 2 LAST CDS_SEC 1
J 0
(-7550 3125);
DISPLAY 1.021277 (-7550 3125);
DISPLAY INVISIBLE (-7550 3125);
FORCEPROP 1 LASTPIN (-7600 3025) $PN 1
J 0
(-7590 3005);
DISPLAY 0.489362 (-7590 3005);
FORCEPROP 1 LASTPIN (-7600 2825) $PN 2
J 0
(-7590 2805);
DISPLAY 0.489362 (-7590 2805);
FORCEPROP 1 LAST MATERIAL X6S
J 0
(-7550 2825);
DISPLAY 0.489362 (-7550 2825);
PAINT SKYBLUE (-7550 2825);
FORCEPROP 1 LAST TOLERANCE 20%
J 0
(-7550 2875);
DISPLAY 0.489362 (-7550 2875);
PAINT SKYBLUE (-7550 2875);
FORCEPROP 1 LAST VALUE 22UF
J 0
(-7550 2975);
DISPLAY 0.489362 (-7550 2975);
PAINT SKYBLUE (-7550 2975);
FORCEPROP 1 LAST PART_NUMBER CH622KMEB02
J 0
(-7550 2775);
DISPLAY 0.489362 (-7550 2775);
PAINT SKYBLUE (-7550 2775);
FORCEPROP 1 LAST VOLTAGE 4V
J 0
(-7550 2925);
DISPLAY 0.489362 (-7550 2925);
PAINT SKYBLUE (-7550 2925);
FORCEPROP 1 LAST PACK_TYPE C0402
J 0
(-7550 2725);
DISPLAY 0.489362 (-7550 2725);
PAINT SKYBLUE (-7550 2725);
FORCEPROP 2 LAST CDS_LIB pure_quanta
J 0
(-7600 2925);
PAINT MONO (-7600 2925);
DISPLAY INVISIBLE (-7600 2925);
FORCEPROP 1 LAST PATH I29
J 0
(-7550 3075);
DISPLAY 0.978723 (-7550 3075);
PAINT WHITE (-7550 3075);
DISPLAY INVISIBLE (-7550 3075);
FORCEADD Q_CAP..1
(-8950 1325);
FORCEPROP 1 LAST LOCATION C2304
J 0
(-8900 1425);
DISPLAY 0.489362 (-8900 1425);
PAINT SKYBLUE (-8900 1425);
FORCEPROP 2 LAST $SEC 1
J 0
(-8900 1525);
DISPLAY 0.680851 (-8900 1525);
PAINT MONO (-8900 1525);
DISPLAY INVISIBLE (-8900 1525);
FORCEPROP 2 LAST CDS_SEC 1
J 0
(-8900 1525);
DISPLAY 1.021277 (-8900 1525);
DISPLAY INVISIBLE (-8900 1525);
FORCEPROP 1 LASTPIN (-8950 1425) $PN 1
J 0
(-8940 1405);
DISPLAY 0.489362 (-8940 1405);
FORCEPROP 1 LASTPIN (-8950 1225) $PN 2
J 0
(-8940 1205);
DISPLAY 0.489362 (-8940 1205);
FORCEPROP 1 LAST MATERIAL X6S
J 0
(-8900 1225);
DISPLAY 0.489362 (-8900 1225);
PAINT SKYBLUE (-8900 1225);
FORCEPROP 1 LAST TOLERANCE 20%
J 0
(-8900 1275);
DISPLAY 0.489362 (-8900 1275);
PAINT SKYBLUE (-8900 1275);
FORCEPROP 1 LAST VALUE 22UF
J 0
(-8900 1375);
DISPLAY 0.489362 (-8900 1375);
PAINT SKYBLUE (-8900 1375);
FORCEPROP 1 LAST PART_NUMBER CH622KMEB02
J 0
(-8900 1175);
DISPLAY 0.489362 (-8900 1175);
PAINT SKYBLUE (-8900 1175);
FORCEPROP 1 LAST VOLTAGE 4V
J 0
(-8900 1325);
DISPLAY 0.489362 (-8900 1325);
PAINT SKYBLUE (-8900 1325);
FORCEPROP 1 LAST PACK_TYPE C0402
J 0
(-8900 1125);
DISPLAY 0.489362 (-8900 1125);
PAINT SKYBLUE (-8900 1125);
FORCEPROP 2 LAST CDS_LIB pure_quanta
J 0
(-8950 1325);
PAINT MONO (-8950 1325);
DISPLAY INVISIBLE (-8950 1325);
FORCEPROP 1 LAST PATH I3
J 0
(-8900 1475);
DISPLAY 0.978723 (-8900 1475);
PAINT WHITE (-8900 1475);
DISPLAY INVISIBLE (-8900 1475);
FORCEADD Q_CAP..1
(-7150 2925);
FORCEPROP 1 LAST LOCATION C2326
J 0
(-7100 3025);
DISPLAY 0.489362 (-7100 3025);
PAINT SKYBLUE (-7100 3025);
FORCEPROP 2 LAST $SEC 1
J 0
(-7100 3125);
DISPLAY 0.680851 (-7100 3125);
PAINT MONO (-7100 3125);
DISPLAY INVISIBLE (-7100 3125);
FORCEPROP 2 LAST CDS_SEC 1
J 0
(-7100 3125);
DISPLAY 1.021277 (-7100 3125);
DISPLAY INVISIBLE (-7100 3125);
FORCEPROP 1 LASTPIN (-7150 3025) $PN 1
J 0
(-7140 3005);
DISPLAY 0.489362 (-7140 3005);
FORCEPROP 1 LASTPIN (-7150 2825) $PN 2
J 0
(-7140 2805);
DISPLAY 0.489362 (-7140 2805);
FORCEPROP 1 LAST MATERIAL X6S
J 0
(-7100 2825);
DISPLAY 0.489362 (-7100 2825);
PAINT SKYBLUE (-7100 2825);
FORCEPROP 1 LAST TOLERANCE 20%
J 0
(-7100 2875);
DISPLAY 0.489362 (-7100 2875);
PAINT SKYBLUE (-7100 2875);
FORCEPROP 1 LAST VALUE 22UF
J 0
(-7100 2975);
DISPLAY 0.489362 (-7100 2975);
PAINT SKYBLUE (-7100 2975);
FORCEPROP 1 LAST PART_NUMBER CH622KMEB02
J 0
(-7100 2775);
DISPLAY 0.489362 (-7100 2775);
PAINT SKYBLUE (-7100 2775);
FORCEPROP 1 LAST VOLTAGE 4V
J 0
(-7100 2925);
DISPLAY 0.489362 (-7100 2925);
PAINT SKYBLUE (-7100 2925);
FORCEPROP 1 LAST PACK_TYPE C0402
J 0
(-7100 2725);
DISPLAY 0.489362 (-7100 2725);
PAINT SKYBLUE (-7100 2725);
FORCEPROP 2 LAST CDS_LIB pure_quanta
J 0
(-7150 2925);
PAINT MONO (-7150 2925);
DISPLAY INVISIBLE (-7150 2925);
FORCEPROP 1 LAST PATH I30
J 0
(-7100 3075);
DISPLAY 0.978723 (-7100 3075);
PAINT WHITE (-7100 3075);
DISPLAY INVISIBLE (-7100 3075);
FORCEADD Q_CAP..1
(-7600 3725);
FORCEPROP 1 LAST LOCATION C2319
J 0
(-7550 3825);
DISPLAY 0.489362 (-7550 3825);
PAINT SKYBLUE (-7550 3825);
FORCEPROP 2 LAST $SEC 1
J 0
(-7550 3925);
DISPLAY 0.680851 (-7550 3925);
PAINT MONO (-7550 3925);
DISPLAY INVISIBLE (-7550 3925);
FORCEPROP 2 LAST CDS_SEC 1
J 0
(-7550 3925);
DISPLAY 1.021277 (-7550 3925);
DISPLAY INVISIBLE (-7550 3925);
FORCEPROP 1 LASTPIN (-7600 3825) $PN 1
J 0
(-7590 3805);
DISPLAY 0.489362 (-7590 3805);
FORCEPROP 1 LASTPIN (-7600 3625) $PN 2
J 0
(-7590 3605);
DISPLAY 0.489362 (-7590 3605);
FORCEPROP 1 LAST MATERIAL X6S
J 0
(-7550 3625);
DISPLAY 0.489362 (-7550 3625);
PAINT SKYBLUE (-7550 3625);
FORCEPROP 1 LAST TOLERANCE 20%
J 0
(-7550 3675);
DISPLAY 0.489362 (-7550 3675);
PAINT SKYBLUE (-7550 3675);
FORCEPROP 1 LAST VALUE 22UF
J 0
(-7550 3775);
DISPLAY 0.489362 (-7550 3775);
PAINT SKYBLUE (-7550 3775);
FORCEPROP 1 LAST PART_NUMBER CH622KMEB02
J 0
(-7550 3575);
DISPLAY 0.489362 (-7550 3575);
PAINT SKYBLUE (-7550 3575);
FORCEPROP 1 LAST VOLTAGE 4V
J 0
(-7550 3725);
DISPLAY 0.489362 (-7550 3725);
PAINT SKYBLUE (-7550 3725);
FORCEPROP 1 LAST PACK_TYPE C0402
J 0
(-7550 3525);
DISPLAY 0.489362 (-7550 3525);
PAINT SKYBLUE (-7550 3525);
FORCEPROP 2 LAST CDS_LIB pure_quanta
J 0
(-7600 3725);
PAINT MONO (-7600 3725);
DISPLAY INVISIBLE (-7600 3725);
FORCEPROP 1 LAST PATH I31
J 0
(-7550 3875);
DISPLAY 0.978723 (-7550 3875);
PAINT WHITE (-7550 3875);
DISPLAY INVISIBLE (-7550 3875);
FORCEADD Q_CAP..1
(-7150 3725);
FORCEPROP 1 LAST LOCATION C2325
J 0
(-7100 3825);
DISPLAY 0.489362 (-7100 3825);
PAINT SKYBLUE (-7100 3825);
FORCEPROP 2 LAST $SEC 1
J 0
(-7100 3925);
DISPLAY 0.680851 (-7100 3925);
PAINT MONO (-7100 3925);
DISPLAY INVISIBLE (-7100 3925);
FORCEPROP 2 LAST CDS_SEC 1
J 0
(-7100 3925);
DISPLAY 1.021277 (-7100 3925);
DISPLAY INVISIBLE (-7100 3925);
FORCEPROP 1 LASTPIN (-7150 3825) $PN 1
J 0
(-7140 3805);
DISPLAY 0.489362 (-7140 3805);
FORCEPROP 1 LASTPIN (-7150 3625) $PN 2
J 0
(-7140 3605);
DISPLAY 0.489362 (-7140 3605);
FORCEPROP 1 LAST MATERIAL X6S
J 0
(-7100 3625);
DISPLAY 0.489362 (-7100 3625);
PAINT SKYBLUE (-7100 3625);
FORCEPROP 1 LAST TOLERANCE 20%
J 0
(-7100 3675);
DISPLAY 0.489362 (-7100 3675);
PAINT SKYBLUE (-7100 3675);
FORCEPROP 1 LAST VALUE 22UF
J 0
(-7100 3775);
DISPLAY 0.489362 (-7100 3775);
PAINT SKYBLUE (-7100 3775);
FORCEPROP 1 LAST PART_NUMBER CH622KMEB02
J 0
(-7100 3575);
DISPLAY 0.489362 (-7100 3575);
PAINT SKYBLUE (-7100 3575);
FORCEPROP 1 LAST VOLTAGE 4V
J 0
(-7100 3725);
DISPLAY 0.489362 (-7100 3725);
PAINT SKYBLUE (-7100 3725);
FORCEPROP 1 LAST PACK_TYPE C0402
J 0
(-7100 3525);
DISPLAY 0.489362 (-7100 3525);
PAINT SKYBLUE (-7100 3525);
FORCEPROP 2 LAST CDS_LIB pure_quanta
J 0
(-7150 3725);
PAINT MONO (-7150 3725);
DISPLAY INVISIBLE (-7150 3725);
FORCEPROP 1 LAST PATH I32
J 0
(-7100 3875);
DISPLAY 0.978723 (-7100 3875);
PAINT WHITE (-7100 3875);
DISPLAY INVISIBLE (-7100 3875);
FORCEADD Q_CAP..1
(-6700 2125);
FORCEPROP 1 LAST LOCATION C2333
J 0
(-6650 2225);
DISPLAY 0.489362 (-6650 2225);
PAINT SKYBLUE (-6650 2225);
FORCEPROP 2 LAST $SEC 1
J 0
(-6650 2325);
DISPLAY 0.680851 (-6650 2325);
PAINT MONO (-6650 2325);
DISPLAY INVISIBLE (-6650 2325);
FORCEPROP 2 LAST CDS_SEC 1
J 0
(-6650 2325);
DISPLAY 1.021277 (-6650 2325);
DISPLAY INVISIBLE (-6650 2325);
FORCEPROP 1 LASTPIN (-6700 2225) $PN 1
J 0
(-6690 2205);
DISPLAY 0.489362 (-6690 2205);
FORCEPROP 1 LASTPIN (-6700 2025) $PN 2
J 0
(-6690 2005);
DISPLAY 0.489362 (-6690 2005);
FORCEPROP 1 LAST MATERIAL X6S
J 0
(-6650 2025);
DISPLAY 0.489362 (-6650 2025);
PAINT SKYBLUE (-6650 2025);
FORCEPROP 1 LAST TOLERANCE 20%
J 0
(-6650 2075);
DISPLAY 0.489362 (-6650 2075);
PAINT SKYBLUE (-6650 2075);
FORCEPROP 1 LAST VALUE 22UF
J 0
(-6650 2175);
DISPLAY 0.489362 (-6650 2175);
PAINT SKYBLUE (-6650 2175);
FORCEPROP 1 LAST PART_NUMBER CH622KMEB02
J 0
(-6650 1975);
DISPLAY 0.489362 (-6650 1975);
PAINT SKYBLUE (-6650 1975);
FORCEPROP 1 LAST VOLTAGE 4V
J 0
(-6650 2125);
DISPLAY 0.489362 (-6650 2125);
PAINT SKYBLUE (-6650 2125);
FORCEPROP 1 LAST PACK_TYPE C0402
J 0
(-6650 1925);
DISPLAY 0.489362 (-6650 1925);
PAINT SKYBLUE (-6650 1925);
FORCEPROP 2 LAST CDS_LIB pure_quanta
J 0
(-6700 2125);
PAINT MONO (-6700 2125);
DISPLAY INVISIBLE (-6700 2125);
FORCEPROP 1 LAST PATH I33
J 0
(-6650 2275);
DISPLAY 0.978723 (-6650 2275);
PAINT WHITE (-6650 2275);
DISPLAY INVISIBLE (-6650 2275);
FORCEADD Q_CAP..1
(-6250 2125);
FORCEPROP 1 LAST LOCATION C2338
J 0
(-6200 2225);
DISPLAY 0.489362 (-6200 2225);
PAINT SKYBLUE (-6200 2225);
FORCEPROP 2 LAST $SEC 1
J 0
(-6200 2325);
DISPLAY 0.680851 (-6200 2325);
PAINT MONO (-6200 2325);
DISPLAY INVISIBLE (-6200 2325);
FORCEPROP 2 LAST CDS_SEC 1
J 0
(-6200 2325);
DISPLAY 1.021277 (-6200 2325);
DISPLAY INVISIBLE (-6200 2325);
FORCEPROP 1 LASTPIN (-6250 2225) $PN 1
J 0
(-6240 2205);
DISPLAY 0.489362 (-6240 2205);
FORCEPROP 1 LASTPIN (-6250 2025) $PN 2
J 0
(-6240 2005);
DISPLAY 0.489362 (-6240 2005);
FORCEPROP 1 LAST MATERIAL X6S
J 0
(-6200 2025);
DISPLAY 0.489362 (-6200 2025);
PAINT SKYBLUE (-6200 2025);
FORCEPROP 1 LAST TOLERANCE 20%
J 0
(-6200 2075);
DISPLAY 0.489362 (-6200 2075);
PAINT SKYBLUE (-6200 2075);
FORCEPROP 1 LAST VALUE 22UF
J 0
(-6200 2175);
DISPLAY 0.489362 (-6200 2175);
PAINT SKYBLUE (-6200 2175);
FORCEPROP 1 LAST PART_NUMBER CH622KMEB02
J 0
(-6200 1975);
DISPLAY 0.489362 (-6200 1975);
PAINT SKYBLUE (-6200 1975);
FORCEPROP 1 LAST VOLTAGE 4V
J 0
(-6200 2125);
DISPLAY 0.489362 (-6200 2125);
PAINT SKYBLUE (-6200 2125);
FORCEPROP 1 LAST PACK_TYPE C0402
J 0
(-6200 1925);
DISPLAY 0.489362 (-6200 1925);
PAINT SKYBLUE (-6200 1925);
FORCEPROP 2 LAST CDS_LIB pure_quanta
J 0
(-6250 2125);
PAINT MONO (-6250 2125);
DISPLAY INVISIBLE (-6250 2125);
FORCEPROP 1 LAST PATH I34
J 0
(-6200 2275);
DISPLAY 0.978723 (-6200 2275);
PAINT WHITE (-6200 2275);
DISPLAY INVISIBLE (-6200 2275);
FORCEADD Q_CAP..1
(-6700 2925);
FORCEPROP 1 LAST LOCATION C2332
J 0
(-6650 3025);
DISPLAY 0.489362 (-6650 3025);
PAINT SKYBLUE (-6650 3025);
FORCEPROP 2 LAST $SEC 1
J 0
(-6650 3125);
DISPLAY 0.680851 (-6650 3125);
PAINT MONO (-6650 3125);
DISPLAY INVISIBLE (-6650 3125);
FORCEPROP 2 LAST CDS_SEC 1
J 0
(-6650 3125);
DISPLAY 1.021277 (-6650 3125);
DISPLAY INVISIBLE (-6650 3125);
FORCEPROP 1 LASTPIN (-6700 3025) $PN 1
J 0
(-6690 3005);
DISPLAY 0.489362 (-6690 3005);
FORCEPROP 1 LASTPIN (-6700 2825) $PN 2
J 0
(-6690 2805);
DISPLAY 0.489362 (-6690 2805);
FORCEPROP 1 LAST MATERIAL X6S
J 0
(-6650 2825);
DISPLAY 0.489362 (-6650 2825);
PAINT SKYBLUE (-6650 2825);
FORCEPROP 1 LAST TOLERANCE 20%
J 0
(-6650 2875);
DISPLAY 0.489362 (-6650 2875);
PAINT SKYBLUE (-6650 2875);
FORCEPROP 1 LAST VALUE 22UF
J 0
(-6650 2975);
DISPLAY 0.489362 (-6650 2975);
PAINT SKYBLUE (-6650 2975);
FORCEPROP 1 LAST PART_NUMBER CH622KMEB02
J 0
(-6650 2775);
DISPLAY 0.489362 (-6650 2775);
PAINT SKYBLUE (-6650 2775);
FORCEPROP 1 LAST VOLTAGE 4V
J 0
(-6650 2925);
DISPLAY 0.489362 (-6650 2925);
PAINT SKYBLUE (-6650 2925);
FORCEPROP 1 LAST PACK_TYPE C0402
J 0
(-6650 2725);
DISPLAY 0.489362 (-6650 2725);
PAINT SKYBLUE (-6650 2725);
FORCEPROP 2 LAST CDS_LIB pure_quanta
J 0
(-6700 2925);
PAINT MONO (-6700 2925);
DISPLAY INVISIBLE (-6700 2925);
FORCEPROP 1 LAST PATH I35
J 0
(-6650 3075);
DISPLAY 0.978723 (-6650 3075);
PAINT WHITE (-6650 3075);
DISPLAY INVISIBLE (-6650 3075);
FORCEADD Q_CAP..1
(-6700 3725);
FORCEPROP 1 LAST LOCATION C2331
J 0
(-6650 3825);
DISPLAY 0.489362 (-6650 3825);
PAINT SKYBLUE (-6650 3825);
FORCEPROP 2 LAST $SEC 1
J 0
(-6650 3925);
DISPLAY 0.680851 (-6650 3925);
PAINT MONO (-6650 3925);
DISPLAY INVISIBLE (-6650 3925);
FORCEPROP 2 LAST CDS_SEC 1
J 0
(-6650 3925);
DISPLAY 1.021277 (-6650 3925);
DISPLAY INVISIBLE (-6650 3925);
FORCEPROP 1 LASTPIN (-6700 3825) $PN 1
J 0
(-6690 3805);
DISPLAY 0.489362 (-6690 3805);
FORCEPROP 1 LASTPIN (-6700 3625) $PN 2
J 0
(-6690 3605);
DISPLAY 0.489362 (-6690 3605);
FORCEPROP 1 LAST MATERIAL X6S
J 0
(-6650 3625);
DISPLAY 0.489362 (-6650 3625);
PAINT SKYBLUE (-6650 3625);
FORCEPROP 1 LAST TOLERANCE 20%
J 0
(-6650 3675);
DISPLAY 0.489362 (-6650 3675);
PAINT SKYBLUE (-6650 3675);
FORCEPROP 1 LAST VALUE 22UF
J 0
(-6650 3775);
DISPLAY 0.489362 (-6650 3775);
PAINT SKYBLUE (-6650 3775);
FORCEPROP 1 LAST PART_NUMBER CH622KMEB02
J 0
(-6650 3575);
DISPLAY 0.489362 (-6650 3575);
PAINT SKYBLUE (-6650 3575);
FORCEPROP 1 LAST VOLTAGE 4V
J 0
(-6650 3725);
DISPLAY 0.489362 (-6650 3725);
PAINT SKYBLUE (-6650 3725);
FORCEPROP 1 LAST PACK_TYPE C0402
J 0
(-6650 3525);
DISPLAY 0.489362 (-6650 3525);
PAINT SKYBLUE (-6650 3525);
FORCEPROP 2 LAST CDS_LIB pure_quanta
J 0
(-6700 3725);
PAINT MONO (-6700 3725);
DISPLAY INVISIBLE (-6700 3725);
FORCEPROP 1 LAST PATH I36
J 0
(-6650 3875);
DISPLAY 0.978723 (-6650 3875);
PAINT WHITE (-6650 3875);
DISPLAY INVISIBLE (-6650 3875);
FORCEADD Q_CAP..1
(-6250 2925);
FORCEPROP 1 LAST LOCATION C2337
J 0
(-6200 3025);
DISPLAY 0.489362 (-6200 3025);
PAINT SKYBLUE (-6200 3025);
FORCEPROP 2 LAST $SEC 1
J 0
(-6200 3125);
DISPLAY 0.680851 (-6200 3125);
PAINT MONO (-6200 3125);
DISPLAY INVISIBLE (-6200 3125);
FORCEPROP 2 LAST CDS_SEC 1
J 0
(-6200 3125);
DISPLAY 1.021277 (-6200 3125);
DISPLAY INVISIBLE (-6200 3125);
FORCEPROP 1 LASTPIN (-6250 3025) $PN 1
J 0
(-6240 3005);
DISPLAY 0.489362 (-6240 3005);
FORCEPROP 1 LASTPIN (-6250 2825) $PN 2
J 0
(-6240 2805);
DISPLAY 0.489362 (-6240 2805);
FORCEPROP 1 LAST MATERIAL X6S
J 0
(-6200 2825);
DISPLAY 0.489362 (-6200 2825);
PAINT SKYBLUE (-6200 2825);
FORCEPROP 1 LAST TOLERANCE 20%
J 0
(-6200 2875);
DISPLAY 0.489362 (-6200 2875);
PAINT SKYBLUE (-6200 2875);
FORCEPROP 1 LAST VALUE 22UF
J 0
(-6200 2975);
DISPLAY 0.489362 (-6200 2975);
PAINT SKYBLUE (-6200 2975);
FORCEPROP 1 LAST PART_NUMBER CH622KMEB02
J 0
(-6200 2775);
DISPLAY 0.489362 (-6200 2775);
PAINT SKYBLUE (-6200 2775);
FORCEPROP 1 LAST VOLTAGE 4V
J 0
(-6200 2925);
DISPLAY 0.489362 (-6200 2925);
PAINT SKYBLUE (-6200 2925);
FORCEPROP 1 LAST PACK_TYPE C0402
J 0
(-6200 2725);
DISPLAY 0.489362 (-6200 2725);
PAINT SKYBLUE (-6200 2725);
FORCEPROP 2 LAST CDS_LIB pure_quanta
J 0
(-6250 2925);
PAINT MONO (-6250 2925);
DISPLAY INVISIBLE (-6250 2925);
FORCEPROP 1 LAST PATH I37
J 0
(-6200 3075);
DISPLAY 0.978723 (-6200 3075);
PAINT WHITE (-6200 3075);
DISPLAY INVISIBLE (-6200 3075);
FORCEADD Q_CAP..1
(-6250 3725);
FORCEPROP 1 LAST LOCATION C2336
J 0
(-6200 3825);
DISPLAY 0.489362 (-6200 3825);
PAINT SKYBLUE (-6200 3825);
FORCEPROP 2 LAST $SEC 1
J 0
(-6200 3925);
DISPLAY 0.680851 (-6200 3925);
PAINT MONO (-6200 3925);
DISPLAY INVISIBLE (-6200 3925);
FORCEPROP 2 LAST CDS_SEC 1
J 0
(-6200 3925);
DISPLAY 1.021277 (-6200 3925);
DISPLAY INVISIBLE (-6200 3925);
FORCEPROP 1 LASTPIN (-6250 3825) $PN 1
J 0
(-6240 3805);
DISPLAY 0.489362 (-6240 3805);
FORCEPROP 1 LASTPIN (-6250 3625) $PN 2
J 0
(-6240 3605);
DISPLAY 0.489362 (-6240 3605);
FORCEPROP 1 LAST MATERIAL X6S
J 0
(-6200 3625);
DISPLAY 0.489362 (-6200 3625);
PAINT SKYBLUE (-6200 3625);
FORCEPROP 1 LAST TOLERANCE 20%
J 0
(-6200 3675);
DISPLAY 0.489362 (-6200 3675);
PAINT SKYBLUE (-6200 3675);
FORCEPROP 1 LAST VALUE 22UF
J 0
(-6200 3775);
DISPLAY 0.489362 (-6200 3775);
PAINT SKYBLUE (-6200 3775);
FORCEPROP 1 LAST PART_NUMBER CH622KMEB02
J 0
(-6200 3575);
DISPLAY 0.489362 (-6200 3575);
PAINT SKYBLUE (-6200 3575);
FORCEPROP 1 LAST VOLTAGE 4V
J 0
(-6200 3725);
DISPLAY 0.489362 (-6200 3725);
PAINT SKYBLUE (-6200 3725);
FORCEPROP 1 LAST PACK_TYPE C0402
J 0
(-6200 3525);
DISPLAY 0.489362 (-6200 3525);
PAINT SKYBLUE (-6200 3525);
FORCEPROP 2 LAST CDS_LIB pure_quanta
J 0
(-6250 3725);
PAINT MONO (-6250 3725);
DISPLAY INVISIBLE (-6250 3725);
FORCEPROP 1 LAST PATH I38
J 0
(-6200 3875);
DISPLAY 0.978723 (-6200 3875);
PAINT WHITE (-6200 3875);
DISPLAY INVISIBLE (-6200 3875);
FORCEADD UNIVERSAL_POWER..1
(-4825 1600);
FORCEPROP 3 LASTPIN (-4825 1550) SIG_NAME PVDDCR_CPU1_P1\g
J 0
(-4815 1560);
DISPLAY 0.659574 (-4815 1560);
PAINT MONO (-4815 1560);
DISPLAY INVISIBLE (-4815 1560);
FORCEPROP 1 LAST HDL_POWER PVDDCR_CPU1_P1
J 1
(-4825 1650);
DISPLAY 0.489362 (-4825 1650);
PAINT GREEN (-4825 1650);
FORCEPROP 2 LAST CDS_LIB pure_quanta_power
J 0
(-4825 1600);
DISPLAY INVISIBLE (-4825 1600);
FORCEPROP 1 LAST PATH I39
J 0
(-4775 1625);
DISPLAY 0.872340 (-4775 1625);
PAINT AQUA (-4775 1625);
DISPLAY INVISIBLE (-4775 1625);
FORCEADD Q_CAP..1
(-8500 1325);
FORCEPROP 1 LAST LOCATION C2310
J 0
(-8450 1425);
DISPLAY 0.489362 (-8450 1425);
PAINT SKYBLUE (-8450 1425);
FORCEPROP 2 LAST $SEC 1
J 0
(-8450 1525);
DISPLAY 0.680851 (-8450 1525);
PAINT MONO (-8450 1525);
DISPLAY INVISIBLE (-8450 1525);
FORCEPROP 2 LAST CDS_SEC 1
J 0
(-8450 1525);
DISPLAY 1.021277 (-8450 1525);
DISPLAY INVISIBLE (-8450 1525);
FORCEPROP 1 LASTPIN (-8500 1425) $PN 1
J 0
(-8490 1405);
DISPLAY 0.489362 (-8490 1405);
FORCEPROP 1 LASTPIN (-8500 1225) $PN 2
J 0
(-8490 1205);
DISPLAY 0.489362 (-8490 1205);
FORCEPROP 1 LAST MATERIAL X6S
J 0
(-8450 1225);
DISPLAY 0.489362 (-8450 1225);
PAINT SKYBLUE (-8450 1225);
FORCEPROP 1 LAST TOLERANCE 20%
J 0
(-8450 1275);
DISPLAY 0.489362 (-8450 1275);
PAINT SKYBLUE (-8450 1275);
FORCEPROP 1 LAST VALUE 22UF
J 0
(-8450 1375);
DISPLAY 0.489362 (-8450 1375);
PAINT SKYBLUE (-8450 1375);
FORCEPROP 1 LAST PART_NUMBER CH622KMEB02
J 0
(-8450 1175);
DISPLAY 0.489362 (-8450 1175);
PAINT SKYBLUE (-8450 1175);
FORCEPROP 1 LAST VOLTAGE 4V
J 0
(-8450 1325);
DISPLAY 0.489362 (-8450 1325);
PAINT SKYBLUE (-8450 1325);
FORCEPROP 1 LAST PACK_TYPE C0402
J 0
(-8450 1125);
DISPLAY 0.489362 (-8450 1125);
PAINT SKYBLUE (-8450 1125);
FORCEPROP 2 LAST CDS_LIB pure_quanta
J 0
(-8500 1325);
PAINT MONO (-8500 1325);
DISPLAY INVISIBLE (-8500 1325);
FORCEPROP 1 LAST PATH I4
J 0
(-8450 1475);
DISPLAY 0.978723 (-8450 1475);
PAINT WHITE (-8450 1475);
DISPLAY INVISIBLE (-8450 1475);
FORCEADD Q_CAP..1
(-4825 1325);
FORCEPROP 1 LAST LOCATION C2354
J 0
(-4775 1425);
DISPLAY 0.489362 (-4775 1425);
PAINT SKYBLUE (-4775 1425);
FORCEPROP 2 LAST $SEC 1
J 0
(-4775 1525);
DISPLAY 0.680851 (-4775 1525);
PAINT MONO (-4775 1525);
DISPLAY INVISIBLE (-4775 1525);
FORCEPROP 2 LAST CDS_SEC 1
J 0
(-4775 1525);
DISPLAY 1.021277 (-4775 1525);
DISPLAY INVISIBLE (-4775 1525);
FORCEPROP 1 LASTPIN (-4825 1425) $PN 1
J 0
(-4815 1405);
DISPLAY 0.489362 (-4815 1405);
FORCEPROP 1 LASTPIN (-4825 1225) $PN 2
J 0
(-4815 1205);
DISPLAY 0.489362 (-4815 1205);
FORCEPROP 1 LAST MATERIAL X6S
J 0
(-4775 1225);
DISPLAY 0.489362 (-4775 1225);
PAINT SKYBLUE (-4775 1225);
FORCEPROP 1 LAST TOLERANCE 20%
J 0
(-4775 1275);
DISPLAY 0.489362 (-4775 1275);
PAINT SKYBLUE (-4775 1275);
FORCEPROP 1 LAST VALUE 22UF
J 0
(-4775 1375);
DISPLAY 0.489362 (-4775 1375);
PAINT SKYBLUE (-4775 1375);
FORCEPROP 1 LAST PART_NUMBER CH622KMEB02
J 0
(-4775 1175);
DISPLAY 0.489362 (-4775 1175);
PAINT SKYBLUE (-4775 1175);
FORCEPROP 1 LAST VOLTAGE 4V
J 0
(-4775 1325);
DISPLAY 0.489362 (-4775 1325);
PAINT SKYBLUE (-4775 1325);
FORCEPROP 1 LAST PACK_TYPE C0402
J 0
(-4775 1125);
DISPLAY 0.489362 (-4775 1125);
PAINT SKYBLUE (-4775 1125);
FORCEPROP 2 LAST CDS_LIB pure_quanta
J 0
(-4825 1325);
PAINT MONO (-4825 1325);
DISPLAY INVISIBLE (-4825 1325);
FORCEPROP 1 LAST PATH I40
J 0
(-4775 1475);
DISPLAY 0.978723 (-4775 1475);
PAINT WHITE (-4775 1475);
DISPLAY INVISIBLE (-4775 1475);
FORCEADD Q_CAP..1
(-4375 1325);
FORCEPROP 1 LAST LOCATION C2360
J 0
(-4325 1425);
DISPLAY 0.489362 (-4325 1425);
PAINT SKYBLUE (-4325 1425);
FORCEPROP 2 LAST $SEC 1
J 0
(-4325 1525);
DISPLAY 0.680851 (-4325 1525);
PAINT MONO (-4325 1525);
DISPLAY INVISIBLE (-4325 1525);
FORCEPROP 2 LAST CDS_SEC 1
J 0
(-4325 1525);
DISPLAY 1.021277 (-4325 1525);
DISPLAY INVISIBLE (-4325 1525);
FORCEPROP 1 LASTPIN (-4375 1425) $PN 1
J 0
(-4365 1405);
DISPLAY 0.489362 (-4365 1405);
FORCEPROP 1 LASTPIN (-4375 1225) $PN 2
J 0
(-4365 1205);
DISPLAY 0.489362 (-4365 1205);
FORCEPROP 1 LAST MATERIAL X6S
J 0
(-4325 1225);
DISPLAY 0.489362 (-4325 1225);
PAINT SKYBLUE (-4325 1225);
FORCEPROP 1 LAST TOLERANCE 20%
J 0
(-4325 1275);
DISPLAY 0.489362 (-4325 1275);
PAINT SKYBLUE (-4325 1275);
FORCEPROP 1 LAST VALUE 22UF
J 0
(-4325 1375);
DISPLAY 0.489362 (-4325 1375);
PAINT SKYBLUE (-4325 1375);
FORCEPROP 1 LAST PART_NUMBER CH622KMEB02
J 0
(-4325 1175);
DISPLAY 0.489362 (-4325 1175);
PAINT SKYBLUE (-4325 1175);
FORCEPROP 1 LAST VOLTAGE 4V
J 0
(-4325 1325);
DISPLAY 0.489362 (-4325 1325);
PAINT SKYBLUE (-4325 1325);
FORCEPROP 1 LAST PACK_TYPE C0402
J 0
(-4325 1125);
DISPLAY 0.489362 (-4325 1125);
PAINT SKYBLUE (-4325 1125);
FORCEPROP 2 LAST CDS_LIB pure_quanta
J 0
(-4375 1325);
PAINT MONO (-4375 1325);
DISPLAY INVISIBLE (-4375 1325);
FORCEPROP 1 LAST PATH I41
J 0
(-4325 1475);
DISPLAY 0.978723 (-4325 1475);
PAINT WHITE (-4325 1475);
DISPLAY INVISIBLE (-4325 1475);
FORCEADD Q_CAP..1
(-5800 2125);
FORCEPROP 1 LAST LOCATION C2343
J 0
(-5750 2225);
DISPLAY 0.489362 (-5750 2225);
PAINT SKYBLUE (-5750 2225);
FORCEPROP 2 LAST $SEC 1
J 0
(-5750 2325);
DISPLAY 0.680851 (-5750 2325);
PAINT MONO (-5750 2325);
DISPLAY INVISIBLE (-5750 2325);
FORCEPROP 2 LAST CDS_SEC 1
J 0
(-5750 2325);
DISPLAY 1.021277 (-5750 2325);
DISPLAY INVISIBLE (-5750 2325);
FORCEPROP 1 LASTPIN (-5800 2225) $PN 1
J 0
(-5790 2205);
DISPLAY 0.489362 (-5790 2205);
FORCEPROP 1 LASTPIN (-5800 2025) $PN 2
J 0
(-5790 2005);
DISPLAY 0.489362 (-5790 2005);
FORCEPROP 1 LAST MATERIAL X6S
J 0
(-5750 2025);
DISPLAY 0.489362 (-5750 2025);
PAINT SKYBLUE (-5750 2025);
FORCEPROP 1 LAST TOLERANCE 20%
J 0
(-5750 2075);
DISPLAY 0.489362 (-5750 2075);
PAINT SKYBLUE (-5750 2075);
FORCEPROP 1 LAST VALUE 22UF
J 0
(-5750 2175);
DISPLAY 0.489362 (-5750 2175);
PAINT SKYBLUE (-5750 2175);
FORCEPROP 1 LAST PART_NUMBER CH622KMEB02
J 0
(-5750 1975);
DISPLAY 0.489362 (-5750 1975);
PAINT SKYBLUE (-5750 1975);
FORCEPROP 1 LAST VOLTAGE 4V
J 0
(-5750 2125);
DISPLAY 0.489362 (-5750 2125);
PAINT SKYBLUE (-5750 2125);
FORCEPROP 1 LAST PACK_TYPE C0402
J 0
(-5750 1925);
DISPLAY 0.489362 (-5750 1925);
PAINT SKYBLUE (-5750 1925);
FORCEPROP 2 LAST CDS_LIB pure_quanta
J 0
(-5800 2125);
PAINT MONO (-5800 2125);
DISPLAY INVISIBLE (-5800 2125);
FORCEPROP 1 LAST PATH I42
J 0
(-5750 2275);
DISPLAY 0.978723 (-5750 2275);
PAINT WHITE (-5750 2275);
DISPLAY INVISIBLE (-5750 2275);
FORCEADD UNIVERSAL_GND..1
(-5400 1750);
FORCEPROP 3 LASTPIN (-5400 1800) SIG_NAME GND\g
J 0
(-5390 1810);
DISPLAY 0.659574 (-5390 1810);
PAINT MONO (-5390 1810);
DISPLAY INVISIBLE (-5390 1810);
FORCEPROP 2 LAST CDS_LIB pure_quanta_power
J 0
(-5400 1750);
PAINT MONO (-5400 1750);
DISPLAY INVISIBLE (-5400 1750);
FORCEPROP 1 LAST PATH I43
J 0
(-5325 1750);
DISPLAY 0.872340 (-5325 1750);
PAINT AQUA (-5325 1750);
DISPLAY INVISIBLE (-5325 1750);
FORCEPROP 1 LAST HDL_POWER GND
J 1
(-5375 1675);
DISPLAY 0.872340 (-5375 1675);
PAINT GREEN (-5375 1675);
DISPLAY INVISIBLE (-5375 1675);
FORCEADD Q_CAP..1
(-5400 2125);
FORCEPROP 1 LAST LOCATION C2348
J 0
(-5350 2225);
DISPLAY 0.489362 (-5350 2225);
PAINT SKYBLUE (-5350 2225);
FORCEPROP 2 LAST $SEC 1
J 0
(-5350 2325);
DISPLAY 0.680851 (-5350 2325);
PAINT MONO (-5350 2325);
DISPLAY INVISIBLE (-5350 2325);
FORCEPROP 2 LAST CDS_SEC 1
J 0
(-5350 2325);
DISPLAY 1.021277 (-5350 2325);
DISPLAY INVISIBLE (-5350 2325);
FORCEPROP 1 LASTPIN (-5400 2225) $PN 1
J 0
(-5390 2205);
DISPLAY 0.489362 (-5390 2205);
FORCEPROP 1 LASTPIN (-5400 2025) $PN 2
J 0
(-5390 2005);
DISPLAY 0.489362 (-5390 2005);
FORCEPROP 1 LAST MATERIAL X6S
J 0
(-5350 2025);
DISPLAY 0.489362 (-5350 2025);
PAINT SKYBLUE (-5350 2025);
FORCEPROP 1 LAST TOLERANCE 20%
J 0
(-5350 2075);
DISPLAY 0.489362 (-5350 2075);
PAINT SKYBLUE (-5350 2075);
FORCEPROP 1 LAST VALUE 22UF
J 0
(-5350 2175);
DISPLAY 0.489362 (-5350 2175);
PAINT SKYBLUE (-5350 2175);
FORCEPROP 1 LAST PART_NUMBER CH622KMEB02
J 0
(-5350 1975);
DISPLAY 0.489362 (-5350 1975);
PAINT SKYBLUE (-5350 1975);
FORCEPROP 1 LAST VOLTAGE 4V
J 0
(-5350 2125);
DISPLAY 0.489362 (-5350 2125);
PAINT SKYBLUE (-5350 2125);
FORCEPROP 1 LAST PACK_TYPE C0402
J 0
(-5350 1925);
DISPLAY 0.489362 (-5350 1925);
PAINT SKYBLUE (-5350 1925);
FORCEPROP 2 LAST CDS_LIB pure_quanta
J 0
(-5400 2125);
PAINT MONO (-5400 2125);
DISPLAY INVISIBLE (-5400 2125);
FORCEPROP 1 LAST PATH I44
J 0
(-5350 2275);
DISPLAY 0.978723 (-5350 2275);
PAINT WHITE (-5350 2275);
DISPLAY INVISIBLE (-5350 2275);
FORCEADD UNIVERSAL_GND..1
(-5400 2550);
FORCEPROP 3 LASTPIN (-5400 2600) SIG_NAME GND\g
J 0
(-5390 2610);
DISPLAY 0.659574 (-5390 2610);
PAINT MONO (-5390 2610);
DISPLAY INVISIBLE (-5390 2610);
FORCEPROP 2 LAST CDS_LIB pure_quanta_power
J 0
(-5400 2550);
PAINT MONO (-5400 2550);
DISPLAY INVISIBLE (-5400 2550);
FORCEPROP 1 LAST PATH I45
J 0
(-5325 2550);
DISPLAY 0.872340 (-5325 2550);
PAINT AQUA (-5325 2550);
DISPLAY INVISIBLE (-5325 2550);
FORCEPROP 1 LAST HDL_POWER GND
J 1
(-5375 2475);
DISPLAY 0.872340 (-5375 2475);
PAINT GREEN (-5375 2475);
DISPLAY INVISIBLE (-5375 2475);
FORCEADD Q_CAP..1
(-5800 2925);
FORCEPROP 1 LAST LOCATION C2342
J 0
(-5750 3025);
DISPLAY 0.489362 (-5750 3025);
PAINT SKYBLUE (-5750 3025);
FORCEPROP 2 LAST $SEC 1
J 0
(-5750 3125);
DISPLAY 0.680851 (-5750 3125);
PAINT MONO (-5750 3125);
DISPLAY INVISIBLE (-5750 3125);
FORCEPROP 2 LAST CDS_SEC 1
J 0
(-5750 3125);
DISPLAY 1.021277 (-5750 3125);
DISPLAY INVISIBLE (-5750 3125);
FORCEPROP 1 LASTPIN (-5800 3025) $PN 1
J 0
(-5790 3005);
DISPLAY 0.489362 (-5790 3005);
FORCEPROP 1 LASTPIN (-5800 2825) $PN 2
J 0
(-5790 2805);
DISPLAY 0.489362 (-5790 2805);
FORCEPROP 1 LAST MATERIAL X6S
J 0
(-5750 2825);
DISPLAY 0.489362 (-5750 2825);
PAINT SKYBLUE (-5750 2825);
FORCEPROP 1 LAST TOLERANCE 20%
J 0
(-5750 2875);
DISPLAY 0.489362 (-5750 2875);
PAINT SKYBLUE (-5750 2875);
FORCEPROP 1 LAST VALUE 22UF
J 0
(-5750 2975);
DISPLAY 0.489362 (-5750 2975);
PAINT SKYBLUE (-5750 2975);
FORCEPROP 1 LAST PART_NUMBER CH622KMEB02
J 0
(-5750 2775);
DISPLAY 0.489362 (-5750 2775);
PAINT SKYBLUE (-5750 2775);
FORCEPROP 1 LAST VOLTAGE 4V
J 0
(-5750 2925);
DISPLAY 0.489362 (-5750 2925);
PAINT SKYBLUE (-5750 2925);
FORCEPROP 1 LAST PACK_TYPE C0402
J 0
(-5750 2725);
DISPLAY 0.489362 (-5750 2725);
PAINT SKYBLUE (-5750 2725);
FORCEPROP 2 LAST CDS_LIB pure_quanta
J 0
(-5800 2925);
PAINT MONO (-5800 2925);
DISPLAY INVISIBLE (-5800 2925);
FORCEPROP 1 LAST PATH I46
J 0
(-5750 3075);
DISPLAY 0.978723 (-5750 3075);
PAINT WHITE (-5750 3075);
DISPLAY INVISIBLE (-5750 3075);
FORCEADD Q_CAP..1
(-5800 3725);
FORCEPROP 1 LAST LOCATION C2341
J 0
(-5750 3825);
DISPLAY 0.489362 (-5750 3825);
PAINT SKYBLUE (-5750 3825);
FORCEPROP 2 LAST $SEC 1
J 0
(-5750 3925);
DISPLAY 0.680851 (-5750 3925);
PAINT MONO (-5750 3925);
DISPLAY INVISIBLE (-5750 3925);
FORCEPROP 2 LAST CDS_SEC 1
J 0
(-5750 3925);
DISPLAY 1.021277 (-5750 3925);
DISPLAY INVISIBLE (-5750 3925);
FORCEPROP 1 LASTPIN (-5800 3825) $PN 1
J 0
(-5790 3805);
DISPLAY 0.489362 (-5790 3805);
FORCEPROP 1 LASTPIN (-5800 3625) $PN 2
J 0
(-5790 3605);
DISPLAY 0.489362 (-5790 3605);
FORCEPROP 1 LAST MATERIAL X6S
J 0
(-5750 3625);
DISPLAY 0.489362 (-5750 3625);
PAINT SKYBLUE (-5750 3625);
FORCEPROP 1 LAST TOLERANCE 20%
J 0
(-5750 3675);
DISPLAY 0.489362 (-5750 3675);
PAINT SKYBLUE (-5750 3675);
FORCEPROP 1 LAST VALUE 22UF
J 0
(-5750 3775);
DISPLAY 0.489362 (-5750 3775);
PAINT SKYBLUE (-5750 3775);
FORCEPROP 1 LAST PART_NUMBER CH622KMEB02
J 0
(-5750 3575);
DISPLAY 0.489362 (-5750 3575);
PAINT SKYBLUE (-5750 3575);
FORCEPROP 1 LAST VOLTAGE 4V
J 0
(-5750 3725);
DISPLAY 0.489362 (-5750 3725);
PAINT SKYBLUE (-5750 3725);
FORCEPROP 1 LAST PACK_TYPE C0402
J 0
(-5750 3525);
DISPLAY 0.489362 (-5750 3525);
PAINT SKYBLUE (-5750 3525);
FORCEPROP 2 LAST CDS_LIB pure_quanta
J 0
(-5800 3725);
PAINT MONO (-5800 3725);
DISPLAY INVISIBLE (-5800 3725);
FORCEPROP 1 LAST PATH I47
J 0
(-5750 3875);
DISPLAY 0.978723 (-5750 3875);
PAINT WHITE (-5750 3875);
DISPLAY INVISIBLE (-5750 3875);
FORCEADD Q_CAP..1
(-5400 2925);
FORCEPROP 1 LAST LOCATION C2347
J 0
(-5350 3025);
DISPLAY 0.489362 (-5350 3025);
PAINT SKYBLUE (-5350 3025);
FORCEPROP 2 LAST $SEC 1
J 0
(-5350 3125);
DISPLAY 0.680851 (-5350 3125);
PAINT MONO (-5350 3125);
DISPLAY INVISIBLE (-5350 3125);
FORCEPROP 2 LAST CDS_SEC 1
J 0
(-5350 3125);
DISPLAY 1.021277 (-5350 3125);
DISPLAY INVISIBLE (-5350 3125);
FORCEPROP 1 LASTPIN (-5400 3025) $PN 1
J 0
(-5390 3005);
DISPLAY 0.489362 (-5390 3005);
FORCEPROP 1 LASTPIN (-5400 2825) $PN 2
J 0
(-5390 2805);
DISPLAY 0.489362 (-5390 2805);
FORCEPROP 1 LAST MATERIAL X6S
J 0
(-5350 2825);
DISPLAY 0.489362 (-5350 2825);
PAINT SKYBLUE (-5350 2825);
FORCEPROP 1 LAST TOLERANCE 20%
J 0
(-5350 2875);
DISPLAY 0.489362 (-5350 2875);
PAINT SKYBLUE (-5350 2875);
FORCEPROP 1 LAST VALUE 22UF
J 0
(-5350 2975);
DISPLAY 0.489362 (-5350 2975);
PAINT SKYBLUE (-5350 2975);
FORCEPROP 1 LAST PART_NUMBER CH622KMEB02
J 0
(-5350 2775);
DISPLAY 0.489362 (-5350 2775);
PAINT SKYBLUE (-5350 2775);
FORCEPROP 1 LAST VOLTAGE 4V
J 0
(-5350 2925);
DISPLAY 0.489362 (-5350 2925);
PAINT SKYBLUE (-5350 2925);
FORCEPROP 1 LAST PACK_TYPE C0402
J 0
(-5350 2725);
DISPLAY 0.489362 (-5350 2725);
PAINT SKYBLUE (-5350 2725);
FORCEPROP 2 LAST CDS_LIB pure_quanta
J 0
(-5400 2925);
PAINT MONO (-5400 2925);
DISPLAY INVISIBLE (-5400 2925);
FORCEPROP 1 LAST PATH I48
J 0
(-5350 3075);
DISPLAY 0.978723 (-5350 3075);
PAINT WHITE (-5350 3075);
DISPLAY INVISIBLE (-5350 3075);
FORCEADD UNIVERSAL_GND..1
(-5400 3350);
FORCEPROP 3 LASTPIN (-5400 3400) SIG_NAME GND\g
J 0
(-5390 3410);
DISPLAY 0.659574 (-5390 3410);
PAINT MONO (-5390 3410);
DISPLAY INVISIBLE (-5390 3410);
FORCEPROP 2 LAST CDS_LIB pure_quanta_power
J 0
(-5400 3350);
PAINT MONO (-5400 3350);
DISPLAY INVISIBLE (-5400 3350);
FORCEPROP 1 LAST PATH I49
J 0
(-5325 3350);
DISPLAY 0.872340 (-5325 3350);
PAINT AQUA (-5325 3350);
DISPLAY INVISIBLE (-5325 3350);
FORCEPROP 1 LAST HDL_POWER GND
J 1
(-5375 3275);
DISPLAY 0.872340 (-5375 3275);
PAINT GREEN (-5375 3275);
DISPLAY INVISIBLE (-5375 3275);
FORCEADD Q_CAP..1
(-9400 2125);
FORCEPROP 1 LAST LOCATION C2297
J 0
(-9350 2225);
DISPLAY 0.489362 (-9350 2225);
PAINT SKYBLUE (-9350 2225);
FORCEPROP 2 LAST $SEC 1
J 0
(-9350 2325);
DISPLAY 0.680851 (-9350 2325);
PAINT MONO (-9350 2325);
DISPLAY INVISIBLE (-9350 2325);
FORCEPROP 2 LAST CDS_SEC 1
J 0
(-9350 2325);
DISPLAY 1.021277 (-9350 2325);
DISPLAY INVISIBLE (-9350 2325);
FORCEPROP 1 LASTPIN (-9400 2225) $PN 1
J 0
(-9390 2205);
DISPLAY 0.489362 (-9390 2205);
FORCEPROP 1 LASTPIN (-9400 2025) $PN 2
J 0
(-9390 2005);
DISPLAY 0.489362 (-9390 2005);
FORCEPROP 1 LAST MATERIAL X6S
J 0
(-9350 2025);
DISPLAY 0.489362 (-9350 2025);
PAINT SKYBLUE (-9350 2025);
FORCEPROP 1 LAST TOLERANCE 20%
J 0
(-9350 2075);
DISPLAY 0.489362 (-9350 2075);
PAINT SKYBLUE (-9350 2075);
FORCEPROP 1 LAST VALUE 22UF
J 0
(-9350 2175);
DISPLAY 0.489362 (-9350 2175);
PAINT SKYBLUE (-9350 2175);
FORCEPROP 1 LAST PART_NUMBER CH622KMEB02
J 0
(-9350 1975);
DISPLAY 0.489362 (-9350 1975);
PAINT SKYBLUE (-9350 1975);
FORCEPROP 1 LAST VOLTAGE 4V
J 0
(-9350 2125);
DISPLAY 0.489362 (-9350 2125);
PAINT SKYBLUE (-9350 2125);
FORCEPROP 1 LAST PACK_TYPE C0402
J 0
(-9350 1925);
DISPLAY 0.489362 (-9350 1925);
PAINT SKYBLUE (-9350 1925);
FORCEPROP 2 LAST CDS_LIB pure_quanta
J 0
(-9400 2125);
PAINT MONO (-9400 2125);
DISPLAY INVISIBLE (-9400 2125);
FORCEPROP 1 LAST PATH I5
J 0
(-9350 2275);
DISPLAY 0.978723 (-9350 2275);
PAINT WHITE (-9350 2275);
DISPLAY INVISIBLE (-9350 2275);
FORCEADD Q_CAP..1
(-5400 3725);
FORCEPROP 1 LAST LOCATION C2346
J 0
(-5350 3825);
DISPLAY 0.489362 (-5350 3825);
PAINT SKYBLUE (-5350 3825);
FORCEPROP 2 LAST $SEC 1
J 0
(-5350 3925);
DISPLAY 0.680851 (-5350 3925);
PAINT MONO (-5350 3925);
DISPLAY INVISIBLE (-5350 3925);
FORCEPROP 2 LAST CDS_SEC 1
J 0
(-5350 3925);
DISPLAY 1.021277 (-5350 3925);
DISPLAY INVISIBLE (-5350 3925);
FORCEPROP 1 LASTPIN (-5400 3825) $PN 1
J 0
(-5390 3805);
DISPLAY 0.489362 (-5390 3805);
FORCEPROP 1 LASTPIN (-5400 3625) $PN 2
J 0
(-5390 3605);
DISPLAY 0.489362 (-5390 3605);
FORCEPROP 1 LAST MATERIAL X6S
J 0
(-5350 3625);
DISPLAY 0.489362 (-5350 3625);
PAINT SKYBLUE (-5350 3625);
FORCEPROP 1 LAST TOLERANCE 20%
J 0
(-5350 3675);
DISPLAY 0.489362 (-5350 3675);
PAINT SKYBLUE (-5350 3675);
FORCEPROP 1 LAST VALUE 22UF
J 0
(-5350 3775);
DISPLAY 0.489362 (-5350 3775);
PAINT SKYBLUE (-5350 3775);
FORCEPROP 1 LAST PART_NUMBER CH622KMEB02
J 0
(-5350 3575);
DISPLAY 0.489362 (-5350 3575);
PAINT SKYBLUE (-5350 3575);
FORCEPROP 1 LAST VOLTAGE 4V
J 0
(-5350 3725);
DISPLAY 0.489362 (-5350 3725);
PAINT SKYBLUE (-5350 3725);
FORCEPROP 1 LAST PACK_TYPE C0402
J 0
(-5350 3525);
DISPLAY 0.489362 (-5350 3525);
PAINT SKYBLUE (-5350 3525);
FORCEPROP 2 LAST CDS_LIB pure_quanta
J 0
(-5400 3725);
PAINT MONO (-5400 3725);
DISPLAY INVISIBLE (-5400 3725);
FORCEPROP 1 LAST PATH I50
J 0
(-5350 3875);
DISPLAY 0.978723 (-5350 3875);
PAINT WHITE (-5350 3875);
DISPLAY INVISIBLE (-5350 3875);
FORCEADD Q_CAP..1
(-4825 2125);
FORCEPROP 1 LAST LOCATION C2353
J 0
(-4775 2225);
DISPLAY 0.489362 (-4775 2225);
PAINT SKYBLUE (-4775 2225);
FORCEPROP 2 LAST $SEC 1
J 0
(-4775 2325);
DISPLAY 0.680851 (-4775 2325);
PAINT MONO (-4775 2325);
DISPLAY INVISIBLE (-4775 2325);
FORCEPROP 2 LAST CDS_SEC 1
J 0
(-4775 2325);
DISPLAY 1.021277 (-4775 2325);
DISPLAY INVISIBLE (-4775 2325);
FORCEPROP 1 LASTPIN (-4825 2225) $PN 1
J 0
(-4815 2205);
DISPLAY 0.489362 (-4815 2205);
FORCEPROP 1 LASTPIN (-4825 2025) $PN 2
J 0
(-4815 2005);
DISPLAY 0.489362 (-4815 2005);
FORCEPROP 1 LAST MATERIAL X6S
J 0
(-4775 2025);
DISPLAY 0.489362 (-4775 2025);
PAINT SKYBLUE (-4775 2025);
FORCEPROP 1 LAST TOLERANCE 20%
J 0
(-4775 2075);
DISPLAY 0.489362 (-4775 2075);
PAINT SKYBLUE (-4775 2075);
FORCEPROP 1 LAST VALUE 22UF
J 0
(-4775 2175);
DISPLAY 0.489362 (-4775 2175);
PAINT SKYBLUE (-4775 2175);
FORCEPROP 1 LAST PART_NUMBER CH622KMEB02
J 0
(-4775 1975);
DISPLAY 0.489362 (-4775 1975);
PAINT SKYBLUE (-4775 1975);
FORCEPROP 1 LAST VOLTAGE 4V
J 0
(-4775 2125);
DISPLAY 0.489362 (-4775 2125);
PAINT SKYBLUE (-4775 2125);
FORCEPROP 1 LAST PACK_TYPE C0402
J 0
(-4775 1925);
DISPLAY 0.489362 (-4775 1925);
PAINT SKYBLUE (-4775 1925);
FORCEPROP 2 LAST CDS_LIB pure_quanta
J 0
(-4825 2125);
PAINT MONO (-4825 2125);
DISPLAY INVISIBLE (-4825 2125);
FORCEPROP 1 LAST PATH I51
J 0
(-4775 2275);
DISPLAY 0.978723 (-4775 2275);
PAINT WHITE (-4775 2275);
DISPLAY INVISIBLE (-4775 2275);
FORCEADD UNIVERSAL_POWER..1
(-4825 2400);
FORCEPROP 3 LASTPIN (-4825 2350) SIG_NAME PVDDCR_CPU1_P1\g
J 0
(-4815 2360);
DISPLAY 0.659574 (-4815 2360);
PAINT MONO (-4815 2360);
DISPLAY INVISIBLE (-4815 2360);
FORCEPROP 1 LAST HDL_POWER PVDDCR_CPU1_P1
J 1
(-4825 2450);
DISPLAY 0.489362 (-4825 2450);
PAINT GREEN (-4825 2450);
FORCEPROP 2 LAST CDS_LIB pure_quanta_power
J 0
(-4825 2400);
DISPLAY INVISIBLE (-4825 2400);
FORCEPROP 1 LAST PATH I52
J 0
(-4775 2425);
DISPLAY 0.872340 (-4775 2425);
PAINT AQUA (-4775 2425);
DISPLAY INVISIBLE (-4775 2425);
FORCEADD Q_CAP..1
(-4375 2125);
FORCEPROP 1 LAST LOCATION C2359
J 0
(-4325 2225);
DISPLAY 0.489362 (-4325 2225);
PAINT SKYBLUE (-4325 2225);
FORCEPROP 2 LAST $SEC 1
J 0
(-4325 2325);
DISPLAY 0.680851 (-4325 2325);
PAINT MONO (-4325 2325);
DISPLAY INVISIBLE (-4325 2325);
FORCEPROP 2 LAST CDS_SEC 1
J 0
(-4325 2325);
DISPLAY 1.021277 (-4325 2325);
DISPLAY INVISIBLE (-4325 2325);
FORCEPROP 1 LASTPIN (-4375 2225) $PN 1
J 0
(-4365 2205);
DISPLAY 0.489362 (-4365 2205);
FORCEPROP 1 LASTPIN (-4375 2025) $PN 2
J 0
(-4365 2005);
DISPLAY 0.489362 (-4365 2005);
FORCEPROP 1 LAST MATERIAL X6S
J 0
(-4325 2025);
DISPLAY 0.489362 (-4325 2025);
PAINT SKYBLUE (-4325 2025);
FORCEPROP 1 LAST TOLERANCE 20%
J 0
(-4325 2075);
DISPLAY 0.489362 (-4325 2075);
PAINT SKYBLUE (-4325 2075);
FORCEPROP 1 LAST VALUE 22UF
J 0
(-4325 2175);
DISPLAY 0.489362 (-4325 2175);
PAINT SKYBLUE (-4325 2175);
FORCEPROP 1 LAST PART_NUMBER CH622KMEB02
J 0
(-4325 1975);
DISPLAY 0.489362 (-4325 1975);
PAINT SKYBLUE (-4325 1975);
FORCEPROP 1 LAST VOLTAGE 4V
J 0
(-4325 2125);
DISPLAY 0.489362 (-4325 2125);
PAINT SKYBLUE (-4325 2125);
FORCEPROP 1 LAST PACK_TYPE C0402
J 0
(-4325 1925);
DISPLAY 0.489362 (-4325 1925);
PAINT SKYBLUE (-4325 1925);
FORCEPROP 2 LAST CDS_LIB pure_quanta
J 0
(-4375 2125);
PAINT MONO (-4375 2125);
DISPLAY INVISIBLE (-4375 2125);
FORCEPROP 1 LAST PATH I53
J 0
(-4325 2275);
DISPLAY 0.978723 (-4325 2275);
PAINT WHITE (-4325 2275);
DISPLAY INVISIBLE (-4325 2275);
FORCEADD UNIVERSAL_POWER..1
(-4825 3200);
FORCEPROP 3 LASTPIN (-4825 3150) SIG_NAME PVDDCR_CPU1_P1\g
J 0
(-4815 3160);
DISPLAY 0.659574 (-4815 3160);
PAINT MONO (-4815 3160);
DISPLAY INVISIBLE (-4815 3160);
FORCEPROP 1 LAST HDL_POWER PVDDCR_CPU1_P1
J 1
(-4825 3250);
DISPLAY 0.489362 (-4825 3250);
PAINT GREEN (-4825 3250);
FORCEPROP 2 LAST CDS_LIB pure_quanta_power
J 0
(-4825 3200);
DISPLAY INVISIBLE (-4825 3200);
FORCEPROP 1 LAST PATH I54
J 0
(-4775 3225);
DISPLAY 0.872340 (-4775 3225);
PAINT AQUA (-4775 3225);
DISPLAY INVISIBLE (-4775 3225);
FORCEADD Q_CAP..1
(-4825 2925);
FORCEPROP 1 LAST LOCATION C2352
J 0
(-4775 3025);
DISPLAY 0.489362 (-4775 3025);
PAINT SKYBLUE (-4775 3025);
FORCEPROP 2 LAST $SEC 1
J 0
(-4775 3125);
DISPLAY 0.680851 (-4775 3125);
PAINT MONO (-4775 3125);
DISPLAY INVISIBLE (-4775 3125);
FORCEPROP 2 LAST CDS_SEC 1
J 0
(-4775 3125);
DISPLAY 1.021277 (-4775 3125);
DISPLAY INVISIBLE (-4775 3125);
FORCEPROP 1 LASTPIN (-4825 3025) $PN 1
J 0
(-4815 3005);
DISPLAY 0.489362 (-4815 3005);
FORCEPROP 1 LASTPIN (-4825 2825) $PN 2
J 0
(-4815 2805);
DISPLAY 0.489362 (-4815 2805);
FORCEPROP 1 LAST MATERIAL X6S
J 0
(-4775 2825);
DISPLAY 0.489362 (-4775 2825);
PAINT SKYBLUE (-4775 2825);
FORCEPROP 1 LAST TOLERANCE 20%
J 0
(-4775 2875);
DISPLAY 0.489362 (-4775 2875);
PAINT SKYBLUE (-4775 2875);
FORCEPROP 1 LAST VALUE 22UF
J 0
(-4775 2975);
DISPLAY 0.489362 (-4775 2975);
PAINT SKYBLUE (-4775 2975);
FORCEPROP 1 LAST PART_NUMBER CH622KMEB02
J 0
(-4775 2775);
DISPLAY 0.489362 (-4775 2775);
PAINT SKYBLUE (-4775 2775);
FORCEPROP 1 LAST VOLTAGE 4V
J 0
(-4775 2925);
DISPLAY 0.489362 (-4775 2925);
PAINT SKYBLUE (-4775 2925);
FORCEPROP 1 LAST PACK_TYPE C0402
J 0
(-4775 2725);
DISPLAY 0.489362 (-4775 2725);
PAINT SKYBLUE (-4775 2725);
FORCEPROP 2 LAST CDS_LIB pure_quanta
J 0
(-4825 2925);
PAINT MONO (-4825 2925);
DISPLAY INVISIBLE (-4825 2925);
FORCEPROP 1 LAST PATH I55
J 0
(-4775 3075);
DISPLAY 0.978723 (-4775 3075);
PAINT WHITE (-4775 3075);
DISPLAY INVISIBLE (-4775 3075);
FORCEADD Q_CAP..1
(-4825 3725);
FORCEPROP 1 LAST LOCATION C2351
J 0
(-4775 3825);
DISPLAY 0.489362 (-4775 3825);
PAINT SKYBLUE (-4775 3825);
FORCEPROP 2 LAST $SEC 1
J 0
(-4775 3925);
DISPLAY 0.680851 (-4775 3925);
PAINT MONO (-4775 3925);
DISPLAY INVISIBLE (-4775 3925);
FORCEPROP 2 LAST CDS_SEC 1
J 0
(-4775 3925);
DISPLAY 1.021277 (-4775 3925);
DISPLAY INVISIBLE (-4775 3925);
FORCEPROP 1 LASTPIN (-4825 3825) $PN 1
J 0
(-4815 3805);
DISPLAY 0.489362 (-4815 3805);
FORCEPROP 1 LASTPIN (-4825 3625) $PN 2
J 0
(-4815 3605);
DISPLAY 0.489362 (-4815 3605);
FORCEPROP 1 LAST MATERIAL X6S
J 0
(-4775 3625);
DISPLAY 0.489362 (-4775 3625);
PAINT SKYBLUE (-4775 3625);
FORCEPROP 1 LAST TOLERANCE 20%
J 0
(-4775 3675);
DISPLAY 0.489362 (-4775 3675);
PAINT SKYBLUE (-4775 3675);
FORCEPROP 1 LAST VALUE 22UF
J 0
(-4775 3775);
DISPLAY 0.489362 (-4775 3775);
PAINT SKYBLUE (-4775 3775);
FORCEPROP 1 LAST PART_NUMBER CH622KMEB02
J 0
(-4775 3575);
DISPLAY 0.489362 (-4775 3575);
PAINT SKYBLUE (-4775 3575);
FORCEPROP 1 LAST VOLTAGE 4V
J 0
(-4775 3725);
DISPLAY 0.489362 (-4775 3725);
PAINT SKYBLUE (-4775 3725);
FORCEPROP 1 LAST PACK_TYPE C0402
J 0
(-4775 3525);
DISPLAY 0.489362 (-4775 3525);
PAINT SKYBLUE (-4775 3525);
FORCEPROP 2 LAST CDS_LIB pure_quanta
J 0
(-4825 3725);
PAINT MONO (-4825 3725);
DISPLAY INVISIBLE (-4825 3725);
FORCEPROP 1 LAST PATH I56
J 0
(-4775 3875);
DISPLAY 0.978723 (-4775 3875);
PAINT WHITE (-4775 3875);
DISPLAY INVISIBLE (-4775 3875);
FORCEADD Q_CAP..1
(-4375 2925);
FORCEPROP 1 LAST LOCATION C2358
J 0
(-4325 3025);
DISPLAY 0.489362 (-4325 3025);
PAINT SKYBLUE (-4325 3025);
FORCEPROP 2 LAST $SEC 1
J 0
(-4325 3125);
DISPLAY 0.680851 (-4325 3125);
PAINT MONO (-4325 3125);
DISPLAY INVISIBLE (-4325 3125);
FORCEPROP 2 LAST CDS_SEC 1
J 0
(-4325 3125);
DISPLAY 1.021277 (-4325 3125);
DISPLAY INVISIBLE (-4325 3125);
FORCEPROP 1 LASTPIN (-4375 3025) $PN 1
J 0
(-4365 3005);
DISPLAY 0.489362 (-4365 3005);
FORCEPROP 1 LASTPIN (-4375 2825) $PN 2
J 0
(-4365 2805);
DISPLAY 0.489362 (-4365 2805);
FORCEPROP 1 LAST MATERIAL X6S
J 0
(-4325 2825);
DISPLAY 0.489362 (-4325 2825);
PAINT SKYBLUE (-4325 2825);
FORCEPROP 1 LAST TOLERANCE 20%
J 0
(-4325 2875);
DISPLAY 0.489362 (-4325 2875);
PAINT SKYBLUE (-4325 2875);
FORCEPROP 1 LAST VALUE 22UF
J 0
(-4325 2975);
DISPLAY 0.489362 (-4325 2975);
PAINT SKYBLUE (-4325 2975);
FORCEPROP 1 LAST PART_NUMBER CH622KMEB02
J 0
(-4325 2775);
DISPLAY 0.489362 (-4325 2775);
PAINT SKYBLUE (-4325 2775);
FORCEPROP 1 LAST VOLTAGE 4V
J 0
(-4325 2925);
DISPLAY 0.489362 (-4325 2925);
PAINT SKYBLUE (-4325 2925);
FORCEPROP 1 LAST PACK_TYPE C0402
J 0
(-4325 2725);
DISPLAY 0.489362 (-4325 2725);
PAINT SKYBLUE (-4325 2725);
FORCEPROP 2 LAST CDS_LIB pure_quanta
J 0
(-4375 2925);
PAINT MONO (-4375 2925);
DISPLAY INVISIBLE (-4375 2925);
FORCEPROP 1 LAST PATH I57
J 0
(-4325 3075);
DISPLAY 0.978723 (-4325 3075);
PAINT WHITE (-4325 3075);
DISPLAY INVISIBLE (-4325 3075);
FORCEADD Q_CAP..1
(-4375 3725);
FORCEPROP 1 LAST LOCATION C2357
J 0
(-4325 3825);
DISPLAY 0.489362 (-4325 3825);
PAINT SKYBLUE (-4325 3825);
FORCEPROP 2 LAST $SEC 1
J 0
(-4325 3925);
DISPLAY 0.680851 (-4325 3925);
PAINT MONO (-4325 3925);
DISPLAY INVISIBLE (-4325 3925);
FORCEPROP 2 LAST CDS_SEC 1
J 0
(-4325 3925);
DISPLAY 1.021277 (-4325 3925);
DISPLAY INVISIBLE (-4325 3925);
FORCEPROP 1 LASTPIN (-4375 3825) $PN 1
J 0
(-4365 3805);
DISPLAY 0.489362 (-4365 3805);
FORCEPROP 1 LASTPIN (-4375 3625) $PN 2
J 0
(-4365 3605);
DISPLAY 0.489362 (-4365 3605);
FORCEPROP 1 LAST MATERIAL X6S
J 0
(-4325 3625);
DISPLAY 0.489362 (-4325 3625);
PAINT SKYBLUE (-4325 3625);
FORCEPROP 1 LAST TOLERANCE 20%
J 0
(-4325 3675);
DISPLAY 0.489362 (-4325 3675);
PAINT SKYBLUE (-4325 3675);
FORCEPROP 1 LAST VALUE 22UF
J 0
(-4325 3775);
DISPLAY 0.489362 (-4325 3775);
PAINT SKYBLUE (-4325 3775);
FORCEPROP 1 LAST PART_NUMBER CH622KMEB02
J 0
(-4325 3575);
DISPLAY 0.489362 (-4325 3575);
PAINT SKYBLUE (-4325 3575);
FORCEPROP 1 LAST VOLTAGE 4V
J 0
(-4325 3725);
DISPLAY 0.489362 (-4325 3725);
PAINT SKYBLUE (-4325 3725);
FORCEPROP 1 LAST PACK_TYPE C0402
J 0
(-4325 3525);
DISPLAY 0.489362 (-4325 3525);
PAINT SKYBLUE (-4325 3525);
FORCEPROP 2 LAST CDS_LIB pure_quanta
J 0
(-4375 3725);
PAINT MONO (-4375 3725);
DISPLAY INVISIBLE (-4375 3725);
FORCEPROP 1 LAST PATH I58
J 0
(-4325 3875);
DISPLAY 0.978723 (-4325 3875);
PAINT WHITE (-4325 3875);
DISPLAY INVISIBLE (-4325 3875);
FORCEADD Q_CAP..1
(-8050 4500);
FORCEPROP 1 LAST LOCATION C2312
J 0
(-8000 4600);
DISPLAY 0.489362 (-8000 4600);
PAINT SKYBLUE (-8000 4600);
FORCEPROP 2 LAST $SEC 1
J 0
(-8000 4700);
DISPLAY 0.680851 (-8000 4700);
PAINT MONO (-8000 4700);
DISPLAY INVISIBLE (-8000 4700);
FORCEPROP 2 LAST CDS_SEC 1
J 0
(-8000 4700);
DISPLAY 1.021277 (-8000 4700);
DISPLAY INVISIBLE (-8000 4700);
FORCEPROP 1 LASTPIN (-8050 4600) $PN 1
J 0
(-8040 4580);
DISPLAY 0.489362 (-8040 4580);
FORCEPROP 1 LASTPIN (-8050 4400) $PN 2
J 0
(-8040 4380);
DISPLAY 0.489362 (-8040 4380);
FORCEPROP 1 LAST MATERIAL X6S
J 0
(-8000 4400);
DISPLAY 0.489362 (-8000 4400);
PAINT SKYBLUE (-8000 4400);
FORCEPROP 1 LAST TOLERANCE 20%
J 0
(-8000 4450);
DISPLAY 0.489362 (-8000 4450);
PAINT SKYBLUE (-8000 4450);
FORCEPROP 1 LAST VALUE 22UF
J 0
(-8000 4550);
DISPLAY 0.489362 (-8000 4550);
PAINT SKYBLUE (-8000 4550);
FORCEPROP 1 LAST PART_NUMBER CH622KMEB02
J 0
(-8000 4350);
DISPLAY 0.489362 (-8000 4350);
PAINT SKYBLUE (-8000 4350);
FORCEPROP 1 LAST VOLTAGE 4V
J 0
(-8000 4500);
DISPLAY 0.489362 (-8000 4500);
PAINT SKYBLUE (-8000 4500);
FORCEPROP 1 LAST PACK_TYPE C0402
J 0
(-8000 4300);
DISPLAY 0.489362 (-8000 4300);
PAINT SKYBLUE (-8000 4300);
FORCEPROP 2 LAST CDS_LIB pure_quanta
J 0
(-8050 4500);
PAINT MONO (-8050 4500);
DISPLAY INVISIBLE (-8050 4500);
FORCEPROP 1 LAST PATH I59
J 0
(-8000 4650);
DISPLAY 0.978723 (-8000 4650);
PAINT WHITE (-8000 4650);
DISPLAY INVISIBLE (-8000 4650);
FORCEADD UNIVERSAL_POWER..1
(-9400 2400);
FORCEPROP 3 LASTPIN (-9400 2350) SIG_NAME PVDDCR_CPU0_P1\g
J 0
(-9390 2360);
DISPLAY 0.659574 (-9390 2360);
PAINT MONO (-9390 2360);
DISPLAY INVISIBLE (-9390 2360);
FORCEPROP 1 LAST HDL_POWER PVDDCR_CPU0_P1
J 1
(-9400 2450);
DISPLAY 0.489362 (-9400 2450);
PAINT GREEN (-9400 2450);
FORCEPROP 2 LAST CDS_LIB pure_quanta_power
J 0
(-9400 2400);
DISPLAY INVISIBLE (-9400 2400);
FORCEPROP 1 LAST PATH I6
J 0
(-9350 2425);
DISPLAY 0.872340 (-9350 2425);
PAINT AQUA (-9350 2425);
DISPLAY INVISIBLE (-9350 2425);
FORCEADD Q_CAP..1
(-7600 4500);
FORCEPROP 1 LAST LOCATION C2318
J 0
(-7550 4600);
DISPLAY 0.489362 (-7550 4600);
PAINT SKYBLUE (-7550 4600);
FORCEPROP 2 LAST $SEC 1
J 0
(-7550 4700);
DISPLAY 0.680851 (-7550 4700);
PAINT MONO (-7550 4700);
DISPLAY INVISIBLE (-7550 4700);
FORCEPROP 2 LAST CDS_SEC 1
J 0
(-7550 4700);
DISPLAY 1.021277 (-7550 4700);
DISPLAY INVISIBLE (-7550 4700);
FORCEPROP 1 LASTPIN (-7600 4600) $PN 1
J 0
(-7590 4580);
DISPLAY 0.489362 (-7590 4580);
FORCEPROP 1 LASTPIN (-7600 4400) $PN 2
J 0
(-7590 4380);
DISPLAY 0.489362 (-7590 4380);
FORCEPROP 1 LAST MATERIAL X6S
J 0
(-7550 4400);
DISPLAY 0.489362 (-7550 4400);
PAINT SKYBLUE (-7550 4400);
FORCEPROP 1 LAST TOLERANCE 20%
J 0
(-7550 4450);
DISPLAY 0.489362 (-7550 4450);
PAINT SKYBLUE (-7550 4450);
FORCEPROP 1 LAST VALUE 22UF
J 0
(-7550 4550);
DISPLAY 0.489362 (-7550 4550);
PAINT SKYBLUE (-7550 4550);
FORCEPROP 1 LAST PART_NUMBER CH622KMEB02
J 0
(-7550 4350);
DISPLAY 0.489362 (-7550 4350);
PAINT SKYBLUE (-7550 4350);
FORCEPROP 1 LAST VOLTAGE 4V
J 0
(-7550 4500);
DISPLAY 0.489362 (-7550 4500);
PAINT SKYBLUE (-7550 4500);
FORCEPROP 1 LAST PACK_TYPE C0402
J 0
(-7550 4300);
DISPLAY 0.489362 (-7550 4300);
PAINT SKYBLUE (-7550 4300);
FORCEPROP 2 LAST CDS_LIB pure_quanta
J 0
(-7600 4500);
PAINT MONO (-7600 4500);
DISPLAY INVISIBLE (-7600 4500);
FORCEPROP 1 LAST PATH I60
J 0
(-7550 4650);
DISPLAY 0.978723 (-7550 4650);
PAINT WHITE (-7550 4650);
DISPLAY INVISIBLE (-7550 4650);
FORCEADD Q_CAP..1
(-7150 4500);
FORCEPROP 1 LAST LOCATION C2324
J 0
(-7100 4600);
DISPLAY 0.489362 (-7100 4600);
PAINT SKYBLUE (-7100 4600);
FORCEPROP 2 LAST $SEC 1
J 0
(-7100 4700);
DISPLAY 0.680851 (-7100 4700);
PAINT MONO (-7100 4700);
DISPLAY INVISIBLE (-7100 4700);
FORCEPROP 2 LAST CDS_SEC 1
J 0
(-7100 4700);
DISPLAY 1.021277 (-7100 4700);
DISPLAY INVISIBLE (-7100 4700);
FORCEPROP 1 LASTPIN (-7150 4600) $PN 1
J 0
(-7140 4580);
DISPLAY 0.489362 (-7140 4580);
FORCEPROP 1 LASTPIN (-7150 4400) $PN 2
J 0
(-7140 4380);
DISPLAY 0.489362 (-7140 4380);
FORCEPROP 1 LAST MATERIAL X6S
J 0
(-7100 4400);
DISPLAY 0.489362 (-7100 4400);
PAINT SKYBLUE (-7100 4400);
FORCEPROP 1 LAST TOLERANCE 20%
J 0
(-7100 4450);
DISPLAY 0.489362 (-7100 4450);
PAINT SKYBLUE (-7100 4450);
FORCEPROP 1 LAST VALUE 22UF
J 0
(-7100 4550);
DISPLAY 0.489362 (-7100 4550);
PAINT SKYBLUE (-7100 4550);
FORCEPROP 1 LAST PART_NUMBER CH622KMEB02
J 0
(-7100 4350);
DISPLAY 0.489362 (-7100 4350);
PAINT SKYBLUE (-7100 4350);
FORCEPROP 1 LAST VOLTAGE 4V
J 0
(-7100 4500);
DISPLAY 0.489362 (-7100 4500);
PAINT SKYBLUE (-7100 4500);
FORCEPROP 1 LAST PACK_TYPE C0402
J 0
(-7100 4300);
DISPLAY 0.489362 (-7100 4300);
PAINT SKYBLUE (-7100 4300);
FORCEPROP 2 LAST CDS_LIB pure_quanta
J 0
(-7150 4500);
PAINT MONO (-7150 4500);
DISPLAY INVISIBLE (-7150 4500);
FORCEPROP 1 LAST PATH I61
J 0
(-7100 4650);
DISPLAY 0.978723 (-7100 4650);
PAINT WHITE (-7100 4650);
DISPLAY INVISIBLE (-7100 4650);
FORCEADD Q_CAP..1
(-6700 4500);
FORCEPROP 1 LAST LOCATION C2330
J 0
(-6650 4600);
DISPLAY 0.489362 (-6650 4600);
PAINT SKYBLUE (-6650 4600);
FORCEPROP 2 LAST $SEC 1
J 0
(-6650 4700);
DISPLAY 0.680851 (-6650 4700);
PAINT MONO (-6650 4700);
DISPLAY INVISIBLE (-6650 4700);
FORCEPROP 2 LAST CDS_SEC 1
J 0
(-6650 4700);
DISPLAY 1.021277 (-6650 4700);
DISPLAY INVISIBLE (-6650 4700);
FORCEPROP 1 LASTPIN (-6700 4600) $PN 1
J 0
(-6690 4580);
DISPLAY 0.489362 (-6690 4580);
FORCEPROP 1 LASTPIN (-6700 4400) $PN 2
J 0
(-6690 4380);
DISPLAY 0.489362 (-6690 4380);
FORCEPROP 1 LAST MATERIAL X6S
J 0
(-6650 4400);
DISPLAY 0.489362 (-6650 4400);
PAINT SKYBLUE (-6650 4400);
FORCEPROP 1 LAST TOLERANCE 20%
J 0
(-6650 4450);
DISPLAY 0.489362 (-6650 4450);
PAINT SKYBLUE (-6650 4450);
FORCEPROP 1 LAST VALUE 22UF
J 0
(-6650 4550);
DISPLAY 0.489362 (-6650 4550);
PAINT SKYBLUE (-6650 4550);
FORCEPROP 1 LAST PART_NUMBER CH622KMEB02
J 0
(-6650 4350);
DISPLAY 0.489362 (-6650 4350);
PAINT SKYBLUE (-6650 4350);
FORCEPROP 1 LAST VOLTAGE 4V
J 0
(-6650 4500);
DISPLAY 0.489362 (-6650 4500);
PAINT SKYBLUE (-6650 4500);
FORCEPROP 1 LAST PACK_TYPE C0402
J 0
(-6650 4300);
DISPLAY 0.489362 (-6650 4300);
PAINT SKYBLUE (-6650 4300);
FORCEPROP 2 LAST CDS_LIB pure_quanta
J 0
(-6700 4500);
PAINT MONO (-6700 4500);
DISPLAY INVISIBLE (-6700 4500);
FORCEPROP 1 LAST PATH I62
J 0
(-6650 4650);
DISPLAY 0.978723 (-6650 4650);
PAINT WHITE (-6650 4650);
DISPLAY INVISIBLE (-6650 4650);
FORCEADD Q_CAP..1
(-6250 4500);
FORCEPROP 1 LAST LOCATION C2335
J 0
(-6200 4600);
DISPLAY 0.489362 (-6200 4600);
PAINT SKYBLUE (-6200 4600);
FORCEPROP 2 LAST $SEC 1
J 0
(-6200 4700);
DISPLAY 0.680851 (-6200 4700);
PAINT MONO (-6200 4700);
DISPLAY INVISIBLE (-6200 4700);
FORCEPROP 2 LAST CDS_SEC 1
J 0
(-6200 4700);
DISPLAY 1.021277 (-6200 4700);
DISPLAY INVISIBLE (-6200 4700);
FORCEPROP 1 LASTPIN (-6250 4600) $PN 1
J 0
(-6240 4580);
DISPLAY 0.489362 (-6240 4580);
FORCEPROP 1 LASTPIN (-6250 4400) $PN 2
J 0
(-6240 4380);
DISPLAY 0.489362 (-6240 4380);
FORCEPROP 1 LAST MATERIAL X6S
J 0
(-6200 4400);
DISPLAY 0.489362 (-6200 4400);
PAINT SKYBLUE (-6200 4400);
FORCEPROP 1 LAST TOLERANCE 20%
J 0
(-6200 4450);
DISPLAY 0.489362 (-6200 4450);
PAINT SKYBLUE (-6200 4450);
FORCEPROP 1 LAST VALUE 22UF
J 0
(-6200 4550);
DISPLAY 0.489362 (-6200 4550);
PAINT SKYBLUE (-6200 4550);
FORCEPROP 1 LAST PART_NUMBER CH622KMEB02
J 0
(-6200 4350);
DISPLAY 0.489362 (-6200 4350);
PAINT SKYBLUE (-6200 4350);
FORCEPROP 1 LAST VOLTAGE 4V
J 0
(-6200 4500);
DISPLAY 0.489362 (-6200 4500);
PAINT SKYBLUE (-6200 4500);
FORCEPROP 1 LAST PACK_TYPE C0402
J 0
(-6200 4300);
DISPLAY 0.489362 (-6200 4300);
PAINT SKYBLUE (-6200 4300);
FORCEPROP 2 LAST CDS_LIB pure_quanta
J 0
(-6250 4500);
PAINT MONO (-6250 4500);
DISPLAY INVISIBLE (-6250 4500);
FORCEPROP 1 LAST PATH I63
J 0
(-6200 4650);
DISPLAY 0.978723 (-6200 4650);
PAINT WHITE (-6200 4650);
DISPLAY INVISIBLE (-6200 4650);
FORCEADD Q_CAP..1
(-5800 4500);
FORCEPROP 1 LAST LOCATION C2340
J 0
(-5750 4600);
DISPLAY 0.489362 (-5750 4600);
PAINT SKYBLUE (-5750 4600);
FORCEPROP 2 LAST $SEC 1
J 0
(-5750 4700);
DISPLAY 0.680851 (-5750 4700);
PAINT MONO (-5750 4700);
DISPLAY INVISIBLE (-5750 4700);
FORCEPROP 2 LAST CDS_SEC 1
J 0
(-5750 4700);
DISPLAY 1.021277 (-5750 4700);
DISPLAY INVISIBLE (-5750 4700);
FORCEPROP 1 LASTPIN (-5800 4600) $PN 1
J 0
(-5790 4580);
DISPLAY 0.489362 (-5790 4580);
FORCEPROP 1 LASTPIN (-5800 4400) $PN 2
J 0
(-5790 4380);
DISPLAY 0.489362 (-5790 4380);
FORCEPROP 1 LAST MATERIAL X6S
J 0
(-5750 4400);
DISPLAY 0.489362 (-5750 4400);
PAINT SKYBLUE (-5750 4400);
FORCEPROP 1 LAST TOLERANCE 20%
J 0
(-5750 4450);
DISPLAY 0.489362 (-5750 4450);
PAINT SKYBLUE (-5750 4450);
FORCEPROP 1 LAST VALUE 22UF
J 0
(-5750 4550);
DISPLAY 0.489362 (-5750 4550);
PAINT SKYBLUE (-5750 4550);
FORCEPROP 1 LAST PART_NUMBER CH622KMEB02
J 0
(-5750 4350);
DISPLAY 0.489362 (-5750 4350);
PAINT SKYBLUE (-5750 4350);
FORCEPROP 1 LAST VOLTAGE 4V
J 0
(-5750 4500);
DISPLAY 0.489362 (-5750 4500);
PAINT SKYBLUE (-5750 4500);
FORCEPROP 1 LAST PACK_TYPE C0402
J 0
(-5750 4300);
DISPLAY 0.489362 (-5750 4300);
PAINT SKYBLUE (-5750 4300);
FORCEPROP 2 LAST CDS_LIB pure_quanta
J 0
(-5800 4500);
PAINT MONO (-5800 4500);
DISPLAY INVISIBLE (-5800 4500);
FORCEPROP 1 LAST PATH I64
J 0
(-5750 4650);
DISPLAY 0.978723 (-5750 4650);
PAINT WHITE (-5750 4650);
DISPLAY INVISIBLE (-5750 4650);
FORCEADD UNIVERSAL_GND..1
(-5400 4125);
FORCEPROP 3 LASTPIN (-5400 4175) SIG_NAME GND\g
J 0
(-5390 4185);
DISPLAY 0.659574 (-5390 4185);
PAINT MONO (-5390 4185);
DISPLAY INVISIBLE (-5390 4185);
FORCEPROP 2 LAST CDS_LIB pure_quanta_power
J 0
(-5400 4125);
PAINT MONO (-5400 4125);
DISPLAY INVISIBLE (-5400 4125);
FORCEPROP 1 LAST PATH I65
J 0
(-5325 4125);
DISPLAY 0.872340 (-5325 4125);
PAINT AQUA (-5325 4125);
DISPLAY INVISIBLE (-5325 4125);
FORCEPROP 1 LAST HDL_POWER GND
J 1
(-5375 4050);
DISPLAY 0.872340 (-5375 4050);
PAINT GREEN (-5375 4050);
DISPLAY INVISIBLE (-5375 4050);
FORCEADD Q_CAP..1
(-5400 4500);
FORCEPROP 1 LAST LOCATION C2345
J 0
(-5350 4600);
DISPLAY 0.489362 (-5350 4600);
PAINT SKYBLUE (-5350 4600);
FORCEPROP 2 LAST $SEC 1
J 0
(-5350 4700);
DISPLAY 0.680851 (-5350 4700);
PAINT MONO (-5350 4700);
DISPLAY INVISIBLE (-5350 4700);
FORCEPROP 2 LAST CDS_SEC 1
J 0
(-5350 4700);
DISPLAY 1.021277 (-5350 4700);
DISPLAY INVISIBLE (-5350 4700);
FORCEPROP 1 LASTPIN (-5400 4600) $PN 1
J 0
(-5390 4580);
DISPLAY 0.489362 (-5390 4580);
FORCEPROP 1 LASTPIN (-5400 4400) $PN 2
J 0
(-5390 4380);
DISPLAY 0.489362 (-5390 4380);
FORCEPROP 1 LAST MATERIAL X6S
J 0
(-5350 4400);
DISPLAY 0.489362 (-5350 4400);
PAINT SKYBLUE (-5350 4400);
FORCEPROP 1 LAST TOLERANCE 20%
J 0
(-5350 4450);
DISPLAY 0.489362 (-5350 4450);
PAINT SKYBLUE (-5350 4450);
FORCEPROP 1 LAST VALUE 22UF
J 0
(-5350 4550);
DISPLAY 0.489362 (-5350 4550);
PAINT SKYBLUE (-5350 4550);
FORCEPROP 1 LAST PART_NUMBER CH622KMEB02
J 0
(-5350 4350);
DISPLAY 0.489362 (-5350 4350);
PAINT SKYBLUE (-5350 4350);
FORCEPROP 1 LAST VOLTAGE 4V
J 0
(-5350 4500);
DISPLAY 0.489362 (-5350 4500);
PAINT SKYBLUE (-5350 4500);
FORCEPROP 1 LAST PACK_TYPE C0402
J 0
(-5350 4300);
DISPLAY 0.489362 (-5350 4300);
PAINT SKYBLUE (-5350 4300);
FORCEPROP 2 LAST CDS_LIB pure_quanta
J 0
(-5400 4500);
PAINT MONO (-5400 4500);
DISPLAY INVISIBLE (-5400 4500);
FORCEPROP 1 LAST PATH I66
J 0
(-5350 4650);
DISPLAY 0.978723 (-5350 4650);
PAINT WHITE (-5350 4650);
DISPLAY INVISIBLE (-5350 4650);
FORCEADD UNIVERSAL_POWER..1
(-4825 4000);
FORCEPROP 3 LASTPIN (-4825 3950) SIG_NAME PVDDCR_CPU1_P1\g
J 0
(-4815 3960);
DISPLAY 0.659574 (-4815 3960);
PAINT MONO (-4815 3960);
DISPLAY INVISIBLE (-4815 3960);
FORCEPROP 1 LAST HDL_POWER PVDDCR_CPU1_P1
J 1
(-4825 4050);
DISPLAY 0.489362 (-4825 4050);
PAINT GREEN (-4825 4050);
FORCEPROP 2 LAST CDS_LIB pure_quanta_power
J 0
(-4825 4000);
DISPLAY INVISIBLE (-4825 4000);
FORCEPROP 1 LAST PATH I67
J 0
(-4775 4025);
DISPLAY 0.872340 (-4775 4025);
PAINT AQUA (-4775 4025);
DISPLAY INVISIBLE (-4775 4025);
FORCEADD Q_CAP..1
(-4375 4500);
FORCEPROP 1 LAST LOCATION C2356
J 0
(-4325 4600);
DISPLAY 0.489362 (-4325 4600);
PAINT SKYBLUE (-4325 4600);
FORCEPROP 2 LAST $SEC 1
J 0
(-4325 4700);
DISPLAY 0.680851 (-4325 4700);
PAINT MONO (-4325 4700);
DISPLAY INVISIBLE (-4325 4700);
FORCEPROP 2 LAST CDS_SEC 1
J 0
(-4325 4700);
DISPLAY 1.021277 (-4325 4700);
DISPLAY INVISIBLE (-4325 4700);
FORCEPROP 1 LASTPIN (-4375 4600) $PN 1
J 0
(-4365 4580);
DISPLAY 0.489362 (-4365 4580);
FORCEPROP 1 LASTPIN (-4375 4400) $PN 2
J 0
(-4365 4380);
DISPLAY 0.489362 (-4365 4380);
FORCEPROP 1 LAST MATERIAL X6S
J 0
(-4325 4400);
DISPLAY 0.489362 (-4325 4400);
PAINT SKYBLUE (-4325 4400);
FORCEPROP 1 LAST TOLERANCE 20%
J 0
(-4325 4450);
DISPLAY 0.489362 (-4325 4450);
PAINT SKYBLUE (-4325 4450);
FORCEPROP 1 LAST VALUE 22UF
J 0
(-4325 4550);
DISPLAY 0.489362 (-4325 4550);
PAINT SKYBLUE (-4325 4550);
FORCEPROP 1 LAST PART_NUMBER CH622KMEB02
J 0
(-4325 4350);
DISPLAY 0.489362 (-4325 4350);
PAINT SKYBLUE (-4325 4350);
FORCEPROP 1 LAST VOLTAGE 4V
J 0
(-4325 4500);
DISPLAY 0.489362 (-4325 4500);
PAINT SKYBLUE (-4325 4500);
FORCEPROP 1 LAST PACK_TYPE C0402
J 0
(-4325 4300);
DISPLAY 0.489362 (-4325 4300);
PAINT SKYBLUE (-4325 4300);
FORCEPROP 2 LAST CDS_LIB pure_quanta
J 0
(-4375 4500);
PAINT MONO (-4375 4500);
DISPLAY INVISIBLE (-4375 4500);
FORCEPROP 1 LAST PATH I68
J 0
(-4325 4650);
DISPLAY 0.978723 (-4325 4650);
PAINT WHITE (-4325 4650);
DISPLAY INVISIBLE (-4325 4650);
FORCEADD UNIVERSAL_POWER..1
(-4825 4775);
FORCEPROP 3 LASTPIN (-4825 4725) SIG_NAME PVDDCR_CPU1_P1\g
J 0
(-4815 4735);
DISPLAY 0.659574 (-4815 4735);
PAINT MONO (-4815 4735);
DISPLAY INVISIBLE (-4815 4735);
FORCEPROP 1 LAST HDL_POWER PVDDCR_CPU1_P1
J 1
(-4825 4825);
DISPLAY 0.489362 (-4825 4825);
PAINT GREEN (-4825 4825);
FORCEPROP 2 LAST CDS_LIB pure_quanta_power
J 0
(-4825 4775);
DISPLAY INVISIBLE (-4825 4775);
FORCEPROP 1 LAST PATH I69
J 0
(-4775 4800);
DISPLAY 0.872340 (-4775 4800);
PAINT AQUA (-4775 4800);
DISPLAY INVISIBLE (-4775 4800);
FORCEADD Q_CAP..1
(-9400 2925);
FORCEPROP 1 LAST LOCATION C2296
J 0
(-9350 3025);
DISPLAY 0.489362 (-9350 3025);
PAINT SKYBLUE (-9350 3025);
FORCEPROP 2 LAST $SEC 1
J 0
(-9350 3125);
DISPLAY 0.680851 (-9350 3125);
PAINT MONO (-9350 3125);
DISPLAY INVISIBLE (-9350 3125);
FORCEPROP 2 LAST CDS_SEC 1
J 0
(-9350 3125);
DISPLAY 1.021277 (-9350 3125);
DISPLAY INVISIBLE (-9350 3125);
FORCEPROP 1 LASTPIN (-9400 3025) $PN 1
J 0
(-9390 3005);
DISPLAY 0.489362 (-9390 3005);
FORCEPROP 1 LASTPIN (-9400 2825) $PN 2
J 0
(-9390 2805);
DISPLAY 0.489362 (-9390 2805);
FORCEPROP 1 LAST MATERIAL X6S
J 0
(-9350 2825);
DISPLAY 0.489362 (-9350 2825);
PAINT SKYBLUE (-9350 2825);
FORCEPROP 1 LAST TOLERANCE 20%
J 0
(-9350 2875);
DISPLAY 0.489362 (-9350 2875);
PAINT SKYBLUE (-9350 2875);
FORCEPROP 1 LAST VALUE 22UF
J 0
(-9350 2975);
DISPLAY 0.489362 (-9350 2975);
PAINT SKYBLUE (-9350 2975);
FORCEPROP 1 LAST PART_NUMBER CH622KMEB02
J 0
(-9350 2775);
DISPLAY 0.489362 (-9350 2775);
PAINT SKYBLUE (-9350 2775);
FORCEPROP 1 LAST VOLTAGE 4V
J 0
(-9350 2925);
DISPLAY 0.489362 (-9350 2925);
PAINT SKYBLUE (-9350 2925);
FORCEPROP 1 LAST PACK_TYPE C0402
J 0
(-9350 2725);
DISPLAY 0.489362 (-9350 2725);
PAINT SKYBLUE (-9350 2725);
FORCEPROP 2 LAST CDS_LIB pure_quanta
J 0
(-9400 2925);
PAINT MONO (-9400 2925);
DISPLAY INVISIBLE (-9400 2925);
FORCEPROP 1 LAST PATH I7
J 0
(-9350 3075);
DISPLAY 0.978723 (-9350 3075);
PAINT WHITE (-9350 3075);
DISPLAY INVISIBLE (-9350 3075);
FORCEADD Q_CAP..1
(-3925 1325);
FORCEPROP 1 LAST LOCATION C2366
J 0
(-3875 1425);
DISPLAY 0.489362 (-3875 1425);
PAINT SKYBLUE (-3875 1425);
FORCEPROP 2 LAST $SEC 1
J 0
(-3875 1525);
DISPLAY 0.680851 (-3875 1525);
PAINT MONO (-3875 1525);
DISPLAY INVISIBLE (-3875 1525);
FORCEPROP 2 LAST CDS_SEC 1
J 0
(-3875 1525);
DISPLAY 1.021277 (-3875 1525);
DISPLAY INVISIBLE (-3875 1525);
FORCEPROP 1 LASTPIN (-3925 1425) $PN 1
J 0
(-3915 1405);
DISPLAY 0.489362 (-3915 1405);
FORCEPROP 1 LASTPIN (-3925 1225) $PN 2
J 0
(-3915 1205);
DISPLAY 0.489362 (-3915 1205);
FORCEPROP 1 LAST MATERIAL X6S
J 0
(-3875 1225);
DISPLAY 0.489362 (-3875 1225);
PAINT SKYBLUE (-3875 1225);
FORCEPROP 1 LAST TOLERANCE 20%
J 0
(-3875 1275);
DISPLAY 0.489362 (-3875 1275);
PAINT SKYBLUE (-3875 1275);
FORCEPROP 1 LAST VALUE 22UF
J 0
(-3875 1375);
DISPLAY 0.489362 (-3875 1375);
PAINT SKYBLUE (-3875 1375);
FORCEPROP 1 LAST PART_NUMBER CH622KMEB02
J 0
(-3875 1175);
DISPLAY 0.489362 (-3875 1175);
PAINT SKYBLUE (-3875 1175);
FORCEPROP 1 LAST VOLTAGE 4V
J 0
(-3875 1325);
DISPLAY 0.489362 (-3875 1325);
PAINT SKYBLUE (-3875 1325);
FORCEPROP 1 LAST PACK_TYPE C0402
J 0
(-3875 1125);
DISPLAY 0.489362 (-3875 1125);
PAINT SKYBLUE (-3875 1125);
FORCEPROP 2 LAST CDS_LIB pure_quanta
J 0
(-3925 1325);
PAINT MONO (-3925 1325);
DISPLAY INVISIBLE (-3925 1325);
FORCEPROP 1 LAST PATH I70
J 0
(-3875 1475);
DISPLAY 0.978723 (-3875 1475);
PAINT WHITE (-3875 1475);
DISPLAY INVISIBLE (-3875 1475);
FORCEADD Q_CAP..1
(-3475 1325);
FORCEPROP 1 LAST LOCATION C2372
J 0
(-3425 1425);
DISPLAY 0.489362 (-3425 1425);
PAINT SKYBLUE (-3425 1425);
FORCEPROP 2 LAST $SEC 1
J 0
(-3425 1525);
DISPLAY 0.680851 (-3425 1525);
PAINT MONO (-3425 1525);
DISPLAY INVISIBLE (-3425 1525);
FORCEPROP 2 LAST CDS_SEC 1
J 0
(-3425 1525);
DISPLAY 1.021277 (-3425 1525);
DISPLAY INVISIBLE (-3425 1525);
FORCEPROP 1 LASTPIN (-3475 1425) $PN 1
J 0
(-3465 1405);
DISPLAY 0.489362 (-3465 1405);
FORCEPROP 1 LASTPIN (-3475 1225) $PN 2
J 0
(-3465 1205);
DISPLAY 0.489362 (-3465 1205);
FORCEPROP 1 LAST MATERIAL X6S
J 0
(-3425 1225);
DISPLAY 0.489362 (-3425 1225);
PAINT SKYBLUE (-3425 1225);
FORCEPROP 1 LAST TOLERANCE 20%
J 0
(-3425 1275);
DISPLAY 0.489362 (-3425 1275);
PAINT SKYBLUE (-3425 1275);
FORCEPROP 1 LAST VALUE 22UF
J 0
(-3425 1375);
DISPLAY 0.489362 (-3425 1375);
PAINT SKYBLUE (-3425 1375);
FORCEPROP 1 LAST PART_NUMBER CH622KMEB02
J 0
(-3425 1175);
DISPLAY 0.489362 (-3425 1175);
PAINT SKYBLUE (-3425 1175);
FORCEPROP 1 LAST VOLTAGE 4V
J 0
(-3425 1325);
DISPLAY 0.489362 (-3425 1325);
PAINT SKYBLUE (-3425 1325);
FORCEPROP 1 LAST PACK_TYPE C0402
J 0
(-3425 1125);
DISPLAY 0.489362 (-3425 1125);
PAINT SKYBLUE (-3425 1125);
FORCEPROP 2 LAST CDS_LIB pure_quanta
J 0
(-3475 1325);
PAINT MONO (-3475 1325);
DISPLAY INVISIBLE (-3475 1325);
FORCEPROP 1 LAST PATH I71
J 0
(-3425 1475);
DISPLAY 0.978723 (-3425 1475);
PAINT WHITE (-3425 1475);
DISPLAY INVISIBLE (-3425 1475);
FORCEADD Q_CAP..1
(-3025 1325);
FORCEPROP 1 LAST LOCATION C2378
J 0
(-2975 1425);
DISPLAY 0.489362 (-2975 1425);
PAINT SKYBLUE (-2975 1425);
FORCEPROP 2 LAST $SEC 1
J 0
(-2975 1525);
DISPLAY 0.680851 (-2975 1525);
PAINT MONO (-2975 1525);
DISPLAY INVISIBLE (-2975 1525);
FORCEPROP 2 LAST CDS_SEC 1
J 0
(-2975 1525);
DISPLAY 1.021277 (-2975 1525);
DISPLAY INVISIBLE (-2975 1525);
FORCEPROP 1 LASTPIN (-3025 1425) $PN 1
J 0
(-3015 1405);
DISPLAY 0.489362 (-3015 1405);
FORCEPROP 1 LASTPIN (-3025 1225) $PN 2
J 0
(-3015 1205);
DISPLAY 0.489362 (-3015 1205);
FORCEPROP 1 LAST MATERIAL X6S
J 0
(-2975 1225);
DISPLAY 0.489362 (-2975 1225);
PAINT SKYBLUE (-2975 1225);
FORCEPROP 1 LAST TOLERANCE 20%
J 0
(-2975 1275);
DISPLAY 0.489362 (-2975 1275);
PAINT SKYBLUE (-2975 1275);
FORCEPROP 1 LAST VALUE 22UF
J 0
(-2975 1375);
DISPLAY 0.489362 (-2975 1375);
PAINT SKYBLUE (-2975 1375);
FORCEPROP 1 LAST PART_NUMBER CH622KMEB02
J 0
(-2975 1175);
DISPLAY 0.489362 (-2975 1175);
PAINT SKYBLUE (-2975 1175);
FORCEPROP 1 LAST VOLTAGE 4V
J 0
(-2975 1325);
DISPLAY 0.489362 (-2975 1325);
PAINT SKYBLUE (-2975 1325);
FORCEPROP 1 LAST PACK_TYPE C0402
J 0
(-2975 1125);
DISPLAY 0.489362 (-2975 1125);
PAINT SKYBLUE (-2975 1125);
FORCEPROP 2 LAST CDS_LIB pure_quanta
J 0
(-3025 1325);
PAINT MONO (-3025 1325);
DISPLAY INVISIBLE (-3025 1325);
FORCEPROP 1 LAST PATH I72
J 0
(-2975 1475);
DISPLAY 0.978723 (-2975 1475);
PAINT WHITE (-2975 1475);
DISPLAY INVISIBLE (-2975 1475);
FORCEADD UNIVERSAL_GND..1
(-3025 950);
FORCEPROP 3 LASTPIN (-3025 1000) SIG_NAME GND\g
J 0
(-3015 1010);
DISPLAY 0.659574 (-3015 1010);
PAINT MONO (-3015 1010);
DISPLAY INVISIBLE (-3015 1010);
FORCEPROP 2 LAST CDS_LIB pure_quanta_power
J 0
(-3025 950);
DISPLAY INVISIBLE (-3025 950);
FORCEPROP 1 LAST PATH I73
J 0
(-2950 950);
DISPLAY 0.872340 (-2950 950);
PAINT AQUA (-2950 950);
DISPLAY INVISIBLE (-2950 950);
FORCEPROP 1 LAST HDL_POWER GND
J 1
(-3000 875);
DISPLAY 0.872340 (-3000 875);
PAINT GREEN (-3000 875);
DISPLAY INVISIBLE (-3000 875);
FORCEADD Q_CAP..1
(-3925 2125);
FORCEPROP 1 LAST LOCATION C2365
J 0
(-3875 2225);
DISPLAY 0.489362 (-3875 2225);
PAINT SKYBLUE (-3875 2225);
FORCEPROP 2 LAST $SEC 1
J 0
(-3875 2325);
DISPLAY 0.680851 (-3875 2325);
PAINT MONO (-3875 2325);
DISPLAY INVISIBLE (-3875 2325);
FORCEPROP 2 LAST CDS_SEC 1
J 0
(-3875 2325);
DISPLAY 1.021277 (-3875 2325);
DISPLAY INVISIBLE (-3875 2325);
FORCEPROP 1 LASTPIN (-3925 2225) $PN 1
J 0
(-3915 2205);
DISPLAY 0.489362 (-3915 2205);
FORCEPROP 1 LASTPIN (-3925 2025) $PN 2
J 0
(-3915 2005);
DISPLAY 0.489362 (-3915 2005);
FORCEPROP 1 LAST MATERIAL X6S
J 0
(-3875 2025);
DISPLAY 0.489362 (-3875 2025);
PAINT SKYBLUE (-3875 2025);
FORCEPROP 1 LAST TOLERANCE 20%
J 0
(-3875 2075);
DISPLAY 0.489362 (-3875 2075);
PAINT SKYBLUE (-3875 2075);
FORCEPROP 1 LAST VALUE 22UF
J 0
(-3875 2175);
DISPLAY 0.489362 (-3875 2175);
PAINT SKYBLUE (-3875 2175);
FORCEPROP 1 LAST PART_NUMBER CH622KMEB02
J 0
(-3875 1975);
DISPLAY 0.489362 (-3875 1975);
PAINT SKYBLUE (-3875 1975);
FORCEPROP 1 LAST VOLTAGE 4V
J 0
(-3875 2125);
DISPLAY 0.489362 (-3875 2125);
PAINT SKYBLUE (-3875 2125);
FORCEPROP 1 LAST PACK_TYPE C0402
J 0
(-3875 1925);
DISPLAY 0.489362 (-3875 1925);
PAINT SKYBLUE (-3875 1925);
FORCEPROP 2 LAST CDS_LIB pure_quanta
J 0
(-3925 2125);
PAINT MONO (-3925 2125);
DISPLAY INVISIBLE (-3925 2125);
FORCEPROP 1 LAST PATH I74
J 0
(-3875 2275);
DISPLAY 0.978723 (-3875 2275);
PAINT WHITE (-3875 2275);
DISPLAY INVISIBLE (-3875 2275);
FORCEADD Q_CAP..1
(-3475 2125);
FORCEPROP 1 LAST LOCATION C2371
J 0
(-3425 2225);
DISPLAY 0.489362 (-3425 2225);
PAINT SKYBLUE (-3425 2225);
FORCEPROP 2 LAST $SEC 1
J 0
(-3425 2325);
DISPLAY 0.680851 (-3425 2325);
PAINT MONO (-3425 2325);
DISPLAY INVISIBLE (-3425 2325);
FORCEPROP 2 LAST CDS_SEC 1
J 0
(-3425 2325);
DISPLAY 1.021277 (-3425 2325);
DISPLAY INVISIBLE (-3425 2325);
FORCEPROP 1 LASTPIN (-3475 2225) $PN 1
J 0
(-3465 2205);
DISPLAY 0.489362 (-3465 2205);
FORCEPROP 1 LASTPIN (-3475 2025) $PN 2
J 0
(-3465 2005);
DISPLAY 0.489362 (-3465 2005);
FORCEPROP 1 LAST MATERIAL X6S
J 0
(-3425 2025);
DISPLAY 0.489362 (-3425 2025);
PAINT SKYBLUE (-3425 2025);
FORCEPROP 1 LAST TOLERANCE 20%
J 0
(-3425 2075);
DISPLAY 0.489362 (-3425 2075);
PAINT SKYBLUE (-3425 2075);
FORCEPROP 1 LAST VALUE 22UF
J 0
(-3425 2175);
DISPLAY 0.489362 (-3425 2175);
PAINT SKYBLUE (-3425 2175);
FORCEPROP 1 LAST PART_NUMBER CH622KMEB02
J 0
(-3425 1975);
DISPLAY 0.489362 (-3425 1975);
PAINT SKYBLUE (-3425 1975);
FORCEPROP 1 LAST VOLTAGE 4V
J 0
(-3425 2125);
DISPLAY 0.489362 (-3425 2125);
PAINT SKYBLUE (-3425 2125);
FORCEPROP 1 LAST PACK_TYPE C0402
J 0
(-3425 1925);
DISPLAY 0.489362 (-3425 1925);
PAINT SKYBLUE (-3425 1925);
FORCEPROP 2 LAST CDS_LIB pure_quanta
J 0
(-3475 2125);
PAINT MONO (-3475 2125);
DISPLAY INVISIBLE (-3475 2125);
FORCEPROP 1 LAST PATH I75
J 0
(-3425 2275);
DISPLAY 0.978723 (-3425 2275);
PAINT WHITE (-3425 2275);
DISPLAY INVISIBLE (-3425 2275);
FORCEADD Q_CAP..1
(-3925 2925);
FORCEPROP 1 LAST LOCATION C2364
J 0
(-3875 3025);
DISPLAY 0.489362 (-3875 3025);
PAINT SKYBLUE (-3875 3025);
FORCEPROP 2 LAST $SEC 1
J 0
(-3875 3125);
DISPLAY 0.680851 (-3875 3125);
PAINT MONO (-3875 3125);
DISPLAY INVISIBLE (-3875 3125);
FORCEPROP 2 LAST CDS_SEC 1
J 0
(-3875 3125);
DISPLAY 1.021277 (-3875 3125);
DISPLAY INVISIBLE (-3875 3125);
FORCEPROP 1 LASTPIN (-3925 3025) $PN 1
J 0
(-3915 3005);
DISPLAY 0.489362 (-3915 3005);
FORCEPROP 1 LASTPIN (-3925 2825) $PN 2
J 0
(-3915 2805);
DISPLAY 0.489362 (-3915 2805);
FORCEPROP 1 LAST MATERIAL X6S
J 0
(-3875 2825);
DISPLAY 0.489362 (-3875 2825);
PAINT SKYBLUE (-3875 2825);
FORCEPROP 1 LAST TOLERANCE 20%
J 0
(-3875 2875);
DISPLAY 0.489362 (-3875 2875);
PAINT SKYBLUE (-3875 2875);
FORCEPROP 1 LAST VALUE 22UF
J 0
(-3875 2975);
DISPLAY 0.489362 (-3875 2975);
PAINT SKYBLUE (-3875 2975);
FORCEPROP 1 LAST PART_NUMBER CH622KMEB02
J 0
(-3875 2775);
DISPLAY 0.489362 (-3875 2775);
PAINT SKYBLUE (-3875 2775);
FORCEPROP 1 LAST VOLTAGE 4V
J 0
(-3875 2925);
DISPLAY 0.489362 (-3875 2925);
PAINT SKYBLUE (-3875 2925);
FORCEPROP 1 LAST PACK_TYPE C0402
J 0
(-3875 2725);
DISPLAY 0.489362 (-3875 2725);
PAINT SKYBLUE (-3875 2725);
FORCEPROP 2 LAST CDS_LIB pure_quanta
J 0
(-3925 2925);
PAINT MONO (-3925 2925);
DISPLAY INVISIBLE (-3925 2925);
FORCEPROP 1 LAST PATH I76
J 0
(-3875 3075);
DISPLAY 0.978723 (-3875 3075);
PAINT WHITE (-3875 3075);
DISPLAY INVISIBLE (-3875 3075);
FORCEADD Q_CAP..1
(-3925 3725);
FORCEPROP 1 LAST LOCATION C2363
J 0
(-3875 3825);
DISPLAY 0.489362 (-3875 3825);
PAINT SKYBLUE (-3875 3825);
FORCEPROP 2 LAST $SEC 1
J 0
(-3875 3925);
DISPLAY 0.680851 (-3875 3925);
PAINT MONO (-3875 3925);
DISPLAY INVISIBLE (-3875 3925);
FORCEPROP 2 LAST CDS_SEC 1
J 0
(-3875 3925);
DISPLAY 1.021277 (-3875 3925);
DISPLAY INVISIBLE (-3875 3925);
FORCEPROP 1 LASTPIN (-3925 3825) $PN 1
J 0
(-3915 3805);
DISPLAY 0.489362 (-3915 3805);
FORCEPROP 1 LASTPIN (-3925 3625) $PN 2
J 0
(-3915 3605);
DISPLAY 0.489362 (-3915 3605);
FORCEPROP 1 LAST MATERIAL X6S
J 0
(-3875 3625);
DISPLAY 0.489362 (-3875 3625);
PAINT SKYBLUE (-3875 3625);
FORCEPROP 1 LAST TOLERANCE 20%
J 0
(-3875 3675);
DISPLAY 0.489362 (-3875 3675);
PAINT SKYBLUE (-3875 3675);
FORCEPROP 1 LAST VALUE 22UF
J 0
(-3875 3775);
DISPLAY 0.489362 (-3875 3775);
PAINT SKYBLUE (-3875 3775);
FORCEPROP 1 LAST PART_NUMBER CH622KMEB02
J 0
(-3875 3575);
DISPLAY 0.489362 (-3875 3575);
PAINT SKYBLUE (-3875 3575);
FORCEPROP 1 LAST VOLTAGE 4V
J 0
(-3875 3725);
DISPLAY 0.489362 (-3875 3725);
PAINT SKYBLUE (-3875 3725);
FORCEPROP 1 LAST PACK_TYPE C0402
J 0
(-3875 3525);
DISPLAY 0.489362 (-3875 3525);
PAINT SKYBLUE (-3875 3525);
FORCEPROP 2 LAST CDS_LIB pure_quanta
J 0
(-3925 3725);
PAINT MONO (-3925 3725);
DISPLAY INVISIBLE (-3925 3725);
FORCEPROP 1 LAST PATH I77
J 0
(-3875 3875);
DISPLAY 0.978723 (-3875 3875);
PAINT WHITE (-3875 3875);
DISPLAY INVISIBLE (-3875 3875);
FORCEADD Q_CAP..1
(-3475 2925);
FORCEPROP 1 LAST LOCATION C2370
J 0
(-3425 3025);
DISPLAY 0.489362 (-3425 3025);
PAINT SKYBLUE (-3425 3025);
FORCEPROP 2 LAST $SEC 1
J 0
(-3425 3125);
DISPLAY 0.680851 (-3425 3125);
PAINT MONO (-3425 3125);
DISPLAY INVISIBLE (-3425 3125);
FORCEPROP 2 LAST CDS_SEC 1
J 0
(-3425 3125);
DISPLAY 1.021277 (-3425 3125);
DISPLAY INVISIBLE (-3425 3125);
FORCEPROP 1 LASTPIN (-3475 3025) $PN 1
J 0
(-3465 3005);
DISPLAY 0.489362 (-3465 3005);
FORCEPROP 1 LASTPIN (-3475 2825) $PN 2
J 0
(-3465 2805);
DISPLAY 0.489362 (-3465 2805);
FORCEPROP 1 LAST MATERIAL X6S
J 0
(-3425 2825);
DISPLAY 0.489362 (-3425 2825);
PAINT SKYBLUE (-3425 2825);
FORCEPROP 1 LAST TOLERANCE 20%
J 0
(-3425 2875);
DISPLAY 0.489362 (-3425 2875);
PAINT SKYBLUE (-3425 2875);
FORCEPROP 1 LAST VALUE 22UF
J 0
(-3425 2975);
DISPLAY 0.489362 (-3425 2975);
PAINT SKYBLUE (-3425 2975);
FORCEPROP 1 LAST PART_NUMBER CH622KMEB02
J 0
(-3425 2775);
DISPLAY 0.489362 (-3425 2775);
PAINT SKYBLUE (-3425 2775);
FORCEPROP 1 LAST VOLTAGE 4V
J 0
(-3425 2925);
DISPLAY 0.489362 (-3425 2925);
PAINT SKYBLUE (-3425 2925);
FORCEPROP 1 LAST PACK_TYPE C0402
J 0
(-3425 2725);
DISPLAY 0.489362 (-3425 2725);
PAINT SKYBLUE (-3425 2725);
FORCEPROP 2 LAST CDS_LIB pure_quanta
J 0
(-3475 2925);
PAINT MONO (-3475 2925);
DISPLAY INVISIBLE (-3475 2925);
FORCEPROP 1 LAST PATH I78
J 0
(-3425 3075);
DISPLAY 0.978723 (-3425 3075);
PAINT WHITE (-3425 3075);
DISPLAY INVISIBLE (-3425 3075);
FORCEADD Q_CAP..1
(-3475 3725);
FORCEPROP 1 LAST LOCATION C2369
J 0
(-3425 3825);
DISPLAY 0.489362 (-3425 3825);
PAINT SKYBLUE (-3425 3825);
FORCEPROP 2 LAST $SEC 1
J 0
(-3425 3925);
DISPLAY 0.680851 (-3425 3925);
PAINT MONO (-3425 3925);
DISPLAY INVISIBLE (-3425 3925);
FORCEPROP 2 LAST CDS_SEC 1
J 0
(-3425 3925);
DISPLAY 1.021277 (-3425 3925);
DISPLAY INVISIBLE (-3425 3925);
FORCEPROP 1 LASTPIN (-3475 3825) $PN 1
J 0
(-3465 3805);
DISPLAY 0.489362 (-3465 3805);
FORCEPROP 1 LASTPIN (-3475 3625) $PN 2
J 0
(-3465 3605);
DISPLAY 0.489362 (-3465 3605);
FORCEPROP 1 LAST MATERIAL X6S
J 0
(-3425 3625);
DISPLAY 0.489362 (-3425 3625);
PAINT SKYBLUE (-3425 3625);
FORCEPROP 1 LAST TOLERANCE 20%
J 0
(-3425 3675);
DISPLAY 0.489362 (-3425 3675);
PAINT SKYBLUE (-3425 3675);
FORCEPROP 1 LAST VALUE 22UF
J 0
(-3425 3775);
DISPLAY 0.489362 (-3425 3775);
PAINT SKYBLUE (-3425 3775);
FORCEPROP 1 LAST PART_NUMBER CH622KMEB02
J 0
(-3425 3575);
DISPLAY 0.489362 (-3425 3575);
PAINT SKYBLUE (-3425 3575);
FORCEPROP 1 LAST VOLTAGE 4V
J 0
(-3425 3725);
DISPLAY 0.489362 (-3425 3725);
PAINT SKYBLUE (-3425 3725);
FORCEPROP 1 LAST PACK_TYPE C0402
J 0
(-3425 3525);
DISPLAY 0.489362 (-3425 3525);
PAINT SKYBLUE (-3425 3525);
FORCEPROP 2 LAST CDS_LIB pure_quanta
J 0
(-3475 3725);
PAINT MONO (-3475 3725);
DISPLAY INVISIBLE (-3475 3725);
FORCEPROP 1 LAST PATH I79
J 0
(-3425 3875);
DISPLAY 0.978723 (-3425 3875);
PAINT WHITE (-3425 3875);
DISPLAY INVISIBLE (-3425 3875);
FORCEADD UNIVERSAL_POWER..1
(-9400 3200);
FORCEPROP 3 LASTPIN (-9400 3150) SIG_NAME PVDDCR_CPU0_P1\g
J 0
(-9390 3160);
DISPLAY 0.659574 (-9390 3160);
PAINT MONO (-9390 3160);
DISPLAY INVISIBLE (-9390 3160);
FORCEPROP 1 LAST HDL_POWER PVDDCR_CPU0_P1
J 1
(-9400 3250);
DISPLAY 0.489362 (-9400 3250);
PAINT GREEN (-9400 3250);
FORCEPROP 2 LAST CDS_LIB pure_quanta_power
J 0
(-9400 3200);
DISPLAY INVISIBLE (-9400 3200);
FORCEPROP 1 LAST PATH I8
J 0
(-9350 3225);
DISPLAY 0.872340 (-9350 3225);
PAINT AQUA (-9350 3225);
DISPLAY INVISIBLE (-9350 3225);
FORCEADD Q_CAP..1
(-3025 2925);
FORCEPROP 1 LAST LOCATION C2376
J 0
(-2975 3025);
DISPLAY 0.489362 (-2975 3025);
PAINT SKYBLUE (-2975 3025);
FORCEPROP 2 LAST $SEC 1
J 0
(-2975 3125);
DISPLAY 0.680851 (-2975 3125);
PAINT MONO (-2975 3125);
DISPLAY INVISIBLE (-2975 3125);
FORCEPROP 2 LAST CDS_SEC 1
J 0
(-2975 3125);
DISPLAY 1.021277 (-2975 3125);
DISPLAY INVISIBLE (-2975 3125);
FORCEPROP 1 LASTPIN (-3025 3025) $PN 1
J 0
(-3015 3005);
DISPLAY 0.489362 (-3015 3005);
FORCEPROP 1 LASTPIN (-3025 2825) $PN 2
J 0
(-3015 2805);
DISPLAY 0.489362 (-3015 2805);
FORCEPROP 1 LAST MATERIAL X6S
J 0
(-2975 2825);
DISPLAY 0.489362 (-2975 2825);
PAINT SKYBLUE (-2975 2825);
FORCEPROP 1 LAST TOLERANCE 20%
J 0
(-2975 2875);
DISPLAY 0.489362 (-2975 2875);
PAINT SKYBLUE (-2975 2875);
FORCEPROP 1 LAST VALUE 22UF
J 0
(-2975 2975);
DISPLAY 0.489362 (-2975 2975);
PAINT SKYBLUE (-2975 2975);
FORCEPROP 1 LAST PART_NUMBER CH622KMEB02
J 0
(-2975 2775);
DISPLAY 0.489362 (-2975 2775);
PAINT SKYBLUE (-2975 2775);
FORCEPROP 1 LAST VOLTAGE 4V
J 0
(-2975 2925);
DISPLAY 0.489362 (-2975 2925);
PAINT SKYBLUE (-2975 2925);
FORCEPROP 1 LAST PACK_TYPE C0402
J 0
(-2975 2725);
DISPLAY 0.489362 (-2975 2725);
PAINT SKYBLUE (-2975 2725);
FORCEPROP 2 LAST CDS_LIB pure_quanta
J 0
(-3025 2925);
PAINT MONO (-3025 2925);
DISPLAY INVISIBLE (-3025 2925);
FORCEPROP 1 LAST PATH I80
J 0
(-2975 3075);
DISPLAY 0.978723 (-2975 3075);
PAINT WHITE (-2975 3075);
DISPLAY INVISIBLE (-2975 3075);
FORCEADD Q_CAP..1
(-3025 2125);
FORCEPROP 1 LAST LOCATION C2377
J 0
(-2975 2225);
DISPLAY 0.489362 (-2975 2225);
PAINT SKYBLUE (-2975 2225);
FORCEPROP 2 LAST $SEC 1
J 0
(-2975 2325);
DISPLAY 0.680851 (-2975 2325);
PAINT MONO (-2975 2325);
DISPLAY INVISIBLE (-2975 2325);
FORCEPROP 2 LAST CDS_SEC 1
J 0
(-2975 2325);
DISPLAY 1.021277 (-2975 2325);
DISPLAY INVISIBLE (-2975 2325);
FORCEPROP 1 LASTPIN (-3025 2225) $PN 1
J 0
(-3015 2205);
DISPLAY 0.489362 (-3015 2205);
FORCEPROP 1 LASTPIN (-3025 2025) $PN 2
J 0
(-3015 2005);
DISPLAY 0.489362 (-3015 2005);
FORCEPROP 1 LAST MATERIAL X6S
J 0
(-2975 2025);
DISPLAY 0.489362 (-2975 2025);
PAINT SKYBLUE (-2975 2025);
FORCEPROP 1 LAST TOLERANCE 20%
J 0
(-2975 2075);
DISPLAY 0.489362 (-2975 2075);
PAINT SKYBLUE (-2975 2075);
FORCEPROP 1 LAST VALUE 22UF
J 0
(-2975 2175);
DISPLAY 0.489362 (-2975 2175);
PAINT SKYBLUE (-2975 2175);
FORCEPROP 1 LAST PART_NUMBER CH622KMEB02
J 0
(-2975 1975);
DISPLAY 0.489362 (-2975 1975);
PAINT SKYBLUE (-2975 1975);
FORCEPROP 1 LAST VOLTAGE 4V
J 0
(-2975 2125);
DISPLAY 0.489362 (-2975 2125);
PAINT SKYBLUE (-2975 2125);
FORCEPROP 1 LAST PACK_TYPE C0402
J 0
(-2975 1925);
DISPLAY 0.489362 (-2975 1925);
PAINT SKYBLUE (-2975 1925);
FORCEPROP 2 LAST CDS_LIB pure_quanta
J 0
(-3025 2125);
PAINT MONO (-3025 2125);
DISPLAY INVISIBLE (-3025 2125);
FORCEPROP 1 LAST PATH I81
J 0
(-2975 2275);
DISPLAY 0.978723 (-2975 2275);
PAINT WHITE (-2975 2275);
DISPLAY INVISIBLE (-2975 2275);
FORCEADD Q_CAP..1
(-2575 2125);
FORCEPROP 1 LAST LOCATION C2383
J 0
(-2525 2225);
DISPLAY 0.489362 (-2525 2225);
PAINT SKYBLUE (-2525 2225);
FORCEPROP 2 LAST $SEC 1
J 0
(-2525 2325);
DISPLAY 0.680851 (-2525 2325);
PAINT MONO (-2525 2325);
DISPLAY INVISIBLE (-2525 2325);
FORCEPROP 2 LAST CDS_SEC 1
J 0
(-2525 2325);
DISPLAY 1.021277 (-2525 2325);
DISPLAY INVISIBLE (-2525 2325);
FORCEPROP 1 LASTPIN (-2575 2225) $PN 1
J 0
(-2565 2205);
DISPLAY 0.489362 (-2565 2205);
FORCEPROP 1 LASTPIN (-2575 2025) $PN 2
J 0
(-2565 2005);
DISPLAY 0.489362 (-2565 2005);
FORCEPROP 1 LAST MATERIAL X6S
J 0
(-2525 2025);
DISPLAY 0.489362 (-2525 2025);
PAINT SKYBLUE (-2525 2025);
FORCEPROP 1 LAST TOLERANCE 20%
J 0
(-2525 2075);
DISPLAY 0.489362 (-2525 2075);
PAINT SKYBLUE (-2525 2075);
FORCEPROP 1 LAST VALUE 22UF
J 0
(-2525 2175);
DISPLAY 0.489362 (-2525 2175);
PAINT SKYBLUE (-2525 2175);
FORCEPROP 1 LAST PART_NUMBER CH622KMEB02
J 0
(-2525 1975);
DISPLAY 0.489362 (-2525 1975);
PAINT SKYBLUE (-2525 1975);
FORCEPROP 1 LAST VOLTAGE 4V
J 0
(-2525 2125);
DISPLAY 0.489362 (-2525 2125);
PAINT SKYBLUE (-2525 2125);
FORCEPROP 1 LAST PACK_TYPE C0402
J 0
(-2525 1925);
DISPLAY 0.489362 (-2525 1925);
PAINT SKYBLUE (-2525 1925);
FORCEPROP 2 LAST CDS_LIB pure_quanta
J 0
(-2575 2125);
PAINT MONO (-2575 2125);
DISPLAY INVISIBLE (-2575 2125);
FORCEPROP 1 LAST PATH I82
J 0
(-2525 2275);
DISPLAY 0.978723 (-2525 2275);
PAINT WHITE (-2525 2275);
DISPLAY INVISIBLE (-2525 2275);
FORCEADD Q_CAP..1
(-2125 2125);
FORCEPROP 1 LAST LOCATION C2389
J 0
(-2075 2225);
DISPLAY 0.489362 (-2075 2225);
PAINT SKYBLUE (-2075 2225);
FORCEPROP 2 LAST $SEC 1
J 0
(-2075 2325);
DISPLAY 0.680851 (-2075 2325);
PAINT MONO (-2075 2325);
DISPLAY INVISIBLE (-2075 2325);
FORCEPROP 2 LAST CDS_SEC 1
J 0
(-2075 2325);
DISPLAY 1.021277 (-2075 2325);
DISPLAY INVISIBLE (-2075 2325);
FORCEPROP 1 LASTPIN (-2125 2225) $PN 1
J 0
(-2115 2205);
DISPLAY 0.489362 (-2115 2205);
FORCEPROP 1 LASTPIN (-2125 2025) $PN 2
J 0
(-2115 2005);
DISPLAY 0.489362 (-2115 2005);
FORCEPROP 1 LAST MATERIAL X6S
J 0
(-2075 2025);
DISPLAY 0.489362 (-2075 2025);
PAINT SKYBLUE (-2075 2025);
FORCEPROP 1 LAST TOLERANCE 20%
J 0
(-2075 2075);
DISPLAY 0.489362 (-2075 2075);
PAINT SKYBLUE (-2075 2075);
FORCEPROP 1 LAST VALUE 22UF
J 0
(-2075 2175);
DISPLAY 0.489362 (-2075 2175);
PAINT SKYBLUE (-2075 2175);
FORCEPROP 1 LAST PART_NUMBER CH622KMEB02
J 0
(-2075 1975);
DISPLAY 0.489362 (-2075 1975);
PAINT SKYBLUE (-2075 1975);
FORCEPROP 1 LAST VOLTAGE 4V
J 0
(-2075 2125);
DISPLAY 0.489362 (-2075 2125);
PAINT SKYBLUE (-2075 2125);
FORCEPROP 1 LAST PACK_TYPE C0402
J 0
(-2075 1925);
DISPLAY 0.489362 (-2075 1925);
PAINT SKYBLUE (-2075 1925);
FORCEPROP 2 LAST CDS_LIB pure_quanta
J 0
(-2125 2125);
PAINT MONO (-2125 2125);
DISPLAY INVISIBLE (-2125 2125);
FORCEPROP 1 LAST PATH I83
J 0
(-2075 2275);
DISPLAY 0.978723 (-2075 2275);
PAINT WHITE (-2075 2275);
DISPLAY INVISIBLE (-2075 2275);
FORCEADD Q_CAP..1
(-2575 2925);
FORCEPROP 1 LAST LOCATION C2382
J 0
(-2525 3025);
DISPLAY 0.489362 (-2525 3025);
PAINT SKYBLUE (-2525 3025);
FORCEPROP 2 LAST $SEC 1
J 0
(-2525 3125);
DISPLAY 0.680851 (-2525 3125);
PAINT MONO (-2525 3125);
DISPLAY INVISIBLE (-2525 3125);
FORCEPROP 2 LAST CDS_SEC 1
J 0
(-2525 3125);
DISPLAY 1.021277 (-2525 3125);
DISPLAY INVISIBLE (-2525 3125);
FORCEPROP 1 LASTPIN (-2575 3025) $PN 1
J 0
(-2565 3005);
DISPLAY 0.489362 (-2565 3005);
FORCEPROP 1 LASTPIN (-2575 2825) $PN 2
J 0
(-2565 2805);
DISPLAY 0.489362 (-2565 2805);
FORCEPROP 1 LAST MATERIAL X6S
J 0
(-2525 2825);
DISPLAY 0.489362 (-2525 2825);
PAINT SKYBLUE (-2525 2825);
FORCEPROP 1 LAST TOLERANCE 20%
J 0
(-2525 2875);
DISPLAY 0.489362 (-2525 2875);
PAINT SKYBLUE (-2525 2875);
FORCEPROP 1 LAST VALUE 22UF
J 0
(-2525 2975);
DISPLAY 0.489362 (-2525 2975);
PAINT SKYBLUE (-2525 2975);
FORCEPROP 1 LAST PART_NUMBER CH622KMEB02
J 0
(-2525 2775);
DISPLAY 0.489362 (-2525 2775);
PAINT SKYBLUE (-2525 2775);
FORCEPROP 1 LAST VOLTAGE 4V
J 0
(-2525 2925);
DISPLAY 0.489362 (-2525 2925);
PAINT SKYBLUE (-2525 2925);
FORCEPROP 1 LAST PACK_TYPE C0402
J 0
(-2525 2725);
DISPLAY 0.489362 (-2525 2725);
PAINT SKYBLUE (-2525 2725);
FORCEPROP 2 LAST CDS_LIB pure_quanta
J 0
(-2575 2925);
PAINT MONO (-2575 2925);
DISPLAY INVISIBLE (-2575 2925);
FORCEPROP 1 LAST PATH I84
J 0
(-2525 3075);
DISPLAY 0.978723 (-2525 3075);
PAINT WHITE (-2525 3075);
DISPLAY INVISIBLE (-2525 3075);
FORCEADD Q_CAP..1
(-3025 3725);
FORCEPROP 1 LAST LOCATION C2375
J 0
(-2975 3825);
DISPLAY 0.489362 (-2975 3825);
PAINT SKYBLUE (-2975 3825);
FORCEPROP 2 LAST $SEC 1
J 0
(-2975 3925);
DISPLAY 0.680851 (-2975 3925);
PAINT MONO (-2975 3925);
DISPLAY INVISIBLE (-2975 3925);
FORCEPROP 2 LAST CDS_SEC 1
J 0
(-2975 3925);
DISPLAY 1.021277 (-2975 3925);
DISPLAY INVISIBLE (-2975 3925);
FORCEPROP 1 LASTPIN (-3025 3825) $PN 1
J 0
(-3015 3805);
DISPLAY 0.489362 (-3015 3805);
FORCEPROP 1 LASTPIN (-3025 3625) $PN 2
J 0
(-3015 3605);
DISPLAY 0.489362 (-3015 3605);
FORCEPROP 1 LAST MATERIAL X6S
J 0
(-2975 3625);
DISPLAY 0.489362 (-2975 3625);
PAINT SKYBLUE (-2975 3625);
FORCEPROP 1 LAST TOLERANCE 20%
J 0
(-2975 3675);
DISPLAY 0.489362 (-2975 3675);
PAINT SKYBLUE (-2975 3675);
FORCEPROP 1 LAST VALUE 22UF
J 0
(-2975 3775);
DISPLAY 0.489362 (-2975 3775);
PAINT SKYBLUE (-2975 3775);
FORCEPROP 1 LAST PART_NUMBER CH622KMEB02
J 0
(-2975 3575);
DISPLAY 0.489362 (-2975 3575);
PAINT SKYBLUE (-2975 3575);
FORCEPROP 1 LAST VOLTAGE 4V
J 0
(-2975 3725);
DISPLAY 0.489362 (-2975 3725);
PAINT SKYBLUE (-2975 3725);
FORCEPROP 1 LAST PACK_TYPE C0402
J 0
(-2975 3525);
DISPLAY 0.489362 (-2975 3525);
PAINT SKYBLUE (-2975 3525);
FORCEPROP 2 LAST CDS_LIB pure_quanta
J 0
(-3025 3725);
PAINT MONO (-3025 3725);
DISPLAY INVISIBLE (-3025 3725);
FORCEPROP 1 LAST PATH I85
J 0
(-2975 3875);
DISPLAY 0.978723 (-2975 3875);
PAINT WHITE (-2975 3875);
DISPLAY INVISIBLE (-2975 3875);
FORCEADD Q_CAP..1
(-2575 3725);
FORCEPROP 1 LAST LOCATION C2381
J 0
(-2525 3825);
DISPLAY 0.489362 (-2525 3825);
PAINT SKYBLUE (-2525 3825);
FORCEPROP 2 LAST $SEC 1
J 0
(-2525 3925);
DISPLAY 0.680851 (-2525 3925);
PAINT MONO (-2525 3925);
DISPLAY INVISIBLE (-2525 3925);
FORCEPROP 2 LAST CDS_SEC 1
J 0
(-2525 3925);
DISPLAY 1.021277 (-2525 3925);
DISPLAY INVISIBLE (-2525 3925);
FORCEPROP 1 LASTPIN (-2575 3825) $PN 1
J 0
(-2565 3805);
DISPLAY 0.489362 (-2565 3805);
FORCEPROP 1 LASTPIN (-2575 3625) $PN 2
J 0
(-2565 3605);
DISPLAY 0.489362 (-2565 3605);
FORCEPROP 1 LAST MATERIAL X6S
J 0
(-2525 3625);
DISPLAY 0.489362 (-2525 3625);
PAINT SKYBLUE (-2525 3625);
FORCEPROP 1 LAST TOLERANCE 20%
J 0
(-2525 3675);
DISPLAY 0.489362 (-2525 3675);
PAINT SKYBLUE (-2525 3675);
FORCEPROP 1 LAST VALUE 22UF
J 0
(-2525 3775);
DISPLAY 0.489362 (-2525 3775);
PAINT SKYBLUE (-2525 3775);
FORCEPROP 1 LAST PART_NUMBER CH622KMEB02
J 0
(-2525 3575);
DISPLAY 0.489362 (-2525 3575);
PAINT SKYBLUE (-2525 3575);
FORCEPROP 1 LAST VOLTAGE 4V
J 0
(-2525 3725);
DISPLAY 0.489362 (-2525 3725);
PAINT SKYBLUE (-2525 3725);
FORCEPROP 1 LAST PACK_TYPE C0402
J 0
(-2525 3525);
DISPLAY 0.489362 (-2525 3525);
PAINT SKYBLUE (-2525 3525);
FORCEPROP 2 LAST CDS_LIB pure_quanta
J 0
(-2575 3725);
PAINT MONO (-2575 3725);
DISPLAY INVISIBLE (-2575 3725);
FORCEPROP 1 LAST PATH I86
J 0
(-2525 3875);
DISPLAY 0.978723 (-2525 3875);
PAINT WHITE (-2525 3875);
DISPLAY INVISIBLE (-2525 3875);
FORCEADD Q_CAP..1
(-2125 2925);
FORCEPROP 1 LAST LOCATION C2388
J 0
(-2075 3025);
DISPLAY 0.489362 (-2075 3025);
PAINT SKYBLUE (-2075 3025);
FORCEPROP 2 LAST $SEC 1
J 0
(-2075 3125);
DISPLAY 0.680851 (-2075 3125);
PAINT MONO (-2075 3125);
DISPLAY INVISIBLE (-2075 3125);
FORCEPROP 2 LAST CDS_SEC 1
J 0
(-2075 3125);
DISPLAY 1.021277 (-2075 3125);
DISPLAY INVISIBLE (-2075 3125);
FORCEPROP 1 LASTPIN (-2125 3025) $PN 1
J 0
(-2115 3005);
DISPLAY 0.489362 (-2115 3005);
FORCEPROP 1 LASTPIN (-2125 2825) $PN 2
J 0
(-2115 2805);
DISPLAY 0.489362 (-2115 2805);
FORCEPROP 1 LAST MATERIAL X6S
J 0
(-2075 2825);
DISPLAY 0.489362 (-2075 2825);
PAINT SKYBLUE (-2075 2825);
FORCEPROP 1 LAST TOLERANCE 20%
J 0
(-2075 2875);
DISPLAY 0.489362 (-2075 2875);
PAINT SKYBLUE (-2075 2875);
FORCEPROP 1 LAST VALUE 22UF
J 0
(-2075 2975);
DISPLAY 0.489362 (-2075 2975);
PAINT SKYBLUE (-2075 2975);
FORCEPROP 1 LAST PART_NUMBER CH622KMEB02
J 0
(-2075 2775);
DISPLAY 0.489362 (-2075 2775);
PAINT SKYBLUE (-2075 2775);
FORCEPROP 1 LAST VOLTAGE 4V
J 0
(-2075 2925);
DISPLAY 0.489362 (-2075 2925);
PAINT SKYBLUE (-2075 2925);
FORCEPROP 1 LAST PACK_TYPE C0402
J 0
(-2075 2725);
DISPLAY 0.489362 (-2075 2725);
PAINT SKYBLUE (-2075 2725);
FORCEPROP 2 LAST CDS_LIB pure_quanta
J 0
(-2125 2925);
PAINT MONO (-2125 2925);
DISPLAY INVISIBLE (-2125 2925);
FORCEPROP 1 LAST PATH I87
J 0
(-2075 3075);
DISPLAY 0.978723 (-2075 3075);
PAINT WHITE (-2075 3075);
DISPLAY INVISIBLE (-2075 3075);
FORCEADD Q_CAP..1
(-2125 3725);
FORCEPROP 1 LAST LOCATION C2387
J 0
(-2075 3825);
DISPLAY 0.489362 (-2075 3825);
PAINT SKYBLUE (-2075 3825);
FORCEPROP 2 LAST $SEC 1
J 0
(-2075 3925);
DISPLAY 0.680851 (-2075 3925);
PAINT MONO (-2075 3925);
DISPLAY INVISIBLE (-2075 3925);
FORCEPROP 2 LAST CDS_SEC 1
J 0
(-2075 3925);
DISPLAY 1.021277 (-2075 3925);
DISPLAY INVISIBLE (-2075 3925);
FORCEPROP 1 LASTPIN (-2125 3825) $PN 1
J 0
(-2115 3805);
DISPLAY 0.489362 (-2115 3805);
FORCEPROP 1 LASTPIN (-2125 3625) $PN 2
J 0
(-2115 3605);
DISPLAY 0.489362 (-2115 3605);
FORCEPROP 1 LAST MATERIAL X6S
J 0
(-2075 3625);
DISPLAY 0.489362 (-2075 3625);
PAINT SKYBLUE (-2075 3625);
FORCEPROP 1 LAST TOLERANCE 20%
J 0
(-2075 3675);
DISPLAY 0.489362 (-2075 3675);
PAINT SKYBLUE (-2075 3675);
FORCEPROP 1 LAST VALUE 22UF
J 0
(-2075 3775);
DISPLAY 0.489362 (-2075 3775);
PAINT SKYBLUE (-2075 3775);
FORCEPROP 1 LAST PART_NUMBER CH622KMEB02
J 0
(-2075 3575);
DISPLAY 0.489362 (-2075 3575);
PAINT SKYBLUE (-2075 3575);
FORCEPROP 1 LAST VOLTAGE 4V
J 0
(-2075 3725);
DISPLAY 0.489362 (-2075 3725);
PAINT SKYBLUE (-2075 3725);
FORCEPROP 1 LAST PACK_TYPE C0402
J 0
(-2075 3525);
DISPLAY 0.489362 (-2075 3525);
PAINT SKYBLUE (-2075 3525);
FORCEPROP 2 LAST CDS_LIB pure_quanta
J 0
(-2125 3725);
PAINT MONO (-2125 3725);
DISPLAY INVISIBLE (-2125 3725);
FORCEPROP 1 LAST PATH I88
J 0
(-2075 3875);
DISPLAY 0.978723 (-2075 3875);
PAINT WHITE (-2075 3875);
DISPLAY INVISIBLE (-2075 3875);
FORCEADD Q_CAP..1
(-1675 2125);
FORCEPROP 1 LAST LOCATION C2395
J 0
(-1625 2225);
DISPLAY 0.489362 (-1625 2225);
PAINT SKYBLUE (-1625 2225);
FORCEPROP 2 LAST $SEC 1
J 0
(-1625 2325);
DISPLAY 0.680851 (-1625 2325);
PAINT MONO (-1625 2325);
DISPLAY INVISIBLE (-1625 2325);
FORCEPROP 2 LAST CDS_SEC 1
J 0
(-1625 2325);
DISPLAY 1.021277 (-1625 2325);
DISPLAY INVISIBLE (-1625 2325);
FORCEPROP 1 LASTPIN (-1675 2225) $PN 1
J 0
(-1665 2205);
DISPLAY 0.489362 (-1665 2205);
FORCEPROP 1 LASTPIN (-1675 2025) $PN 2
J 0
(-1665 2005);
DISPLAY 0.489362 (-1665 2005);
FORCEPROP 1 LAST MATERIAL X6S
J 0
(-1625 2025);
DISPLAY 0.489362 (-1625 2025);
PAINT SKYBLUE (-1625 2025);
FORCEPROP 1 LAST TOLERANCE 20%
J 0
(-1625 2075);
DISPLAY 0.489362 (-1625 2075);
PAINT SKYBLUE (-1625 2075);
FORCEPROP 1 LAST VALUE 22UF
J 0
(-1625 2175);
DISPLAY 0.489362 (-1625 2175);
PAINT SKYBLUE (-1625 2175);
FORCEPROP 1 LAST PART_NUMBER CH622KMEB02
J 0
(-1625 1975);
DISPLAY 0.489362 (-1625 1975);
PAINT SKYBLUE (-1625 1975);
FORCEPROP 1 LAST VOLTAGE 4V
J 0
(-1625 2125);
DISPLAY 0.489362 (-1625 2125);
PAINT SKYBLUE (-1625 2125);
FORCEPROP 1 LAST PACK_TYPE C0402
J 0
(-1625 1925);
DISPLAY 0.489362 (-1625 1925);
PAINT SKYBLUE (-1625 1925);
FORCEPROP 2 LAST CDS_LIB pure_quanta
J 0
(-1675 2125);
PAINT MONO (-1675 2125);
DISPLAY INVISIBLE (-1675 2125);
FORCEPROP 1 LAST PATH I89
J 0
(-1625 2275);
DISPLAY 0.978723 (-1625 2275);
PAINT WHITE (-1625 2275);
DISPLAY INVISIBLE (-1625 2275);
FORCEADD Q_CAP..1
(-9400 3725);
FORCEPROP 1 LAST LOCATION C2295
J 0
(-9350 3825);
DISPLAY 0.489362 (-9350 3825);
PAINT SKYBLUE (-9350 3825);
FORCEPROP 2 LAST $SEC 1
J 0
(-9350 3925);
DISPLAY 0.680851 (-9350 3925);
PAINT MONO (-9350 3925);
DISPLAY INVISIBLE (-9350 3925);
FORCEPROP 2 LAST CDS_SEC 1
J 0
(-9350 3925);
DISPLAY 1.021277 (-9350 3925);
DISPLAY INVISIBLE (-9350 3925);
FORCEPROP 1 LASTPIN (-9400 3825) $PN 1
J 0
(-9390 3805);
DISPLAY 0.489362 (-9390 3805);
FORCEPROP 1 LASTPIN (-9400 3625) $PN 2
J 0
(-9390 3605);
DISPLAY 0.489362 (-9390 3605);
FORCEPROP 1 LAST MATERIAL X6S
J 0
(-9350 3625);
DISPLAY 0.489362 (-9350 3625);
PAINT SKYBLUE (-9350 3625);
FORCEPROP 1 LAST TOLERANCE 20%
J 0
(-9350 3675);
DISPLAY 0.489362 (-9350 3675);
PAINT SKYBLUE (-9350 3675);
FORCEPROP 1 LAST VALUE 22UF
J 0
(-9350 3775);
DISPLAY 0.489362 (-9350 3775);
PAINT SKYBLUE (-9350 3775);
FORCEPROP 1 LAST PART_NUMBER CH622KMEB02
J 0
(-9350 3575);
DISPLAY 0.489362 (-9350 3575);
PAINT SKYBLUE (-9350 3575);
FORCEPROP 1 LAST VOLTAGE 4V
J 0
(-9350 3725);
DISPLAY 0.489362 (-9350 3725);
PAINT SKYBLUE (-9350 3725);
FORCEPROP 1 LAST PACK_TYPE C0402
J 0
(-9350 3525);
DISPLAY 0.489362 (-9350 3525);
PAINT SKYBLUE (-9350 3525);
FORCEPROP 2 LAST CDS_LIB pure_quanta
J 0
(-9400 3725);
PAINT MONO (-9400 3725);
DISPLAY INVISIBLE (-9400 3725);
FORCEPROP 1 LAST PATH I9
J 0
(-9350 3875);
DISPLAY 0.978723 (-9350 3875);
PAINT WHITE (-9350 3875);
DISPLAY INVISIBLE (-9350 3875);
FORCEADD Q_CAP..1
(-1225 2125);
FORCEPROP 1 LAST LOCATION C2400
J 0
(-1175 2225);
DISPLAY 0.489362 (-1175 2225);
PAINT SKYBLUE (-1175 2225);
FORCEPROP 2 LAST $SEC 1
J 0
(-1175 2325);
DISPLAY 0.680851 (-1175 2325);
PAINT MONO (-1175 2325);
DISPLAY INVISIBLE (-1175 2325);
FORCEPROP 2 LAST CDS_SEC 1
J 0
(-1175 2325);
DISPLAY 1.021277 (-1175 2325);
DISPLAY INVISIBLE (-1175 2325);
FORCEPROP 1 LASTPIN (-1225 2225) $PN 1
J 0
(-1215 2205);
DISPLAY 0.489362 (-1215 2205);
FORCEPROP 1 LASTPIN (-1225 2025) $PN 2
J 0
(-1215 2005);
DISPLAY 0.489362 (-1215 2005);
FORCEPROP 1 LAST MATERIAL X6S
J 0
(-1175 2025);
DISPLAY 0.489362 (-1175 2025);
PAINT SKYBLUE (-1175 2025);
FORCEPROP 1 LAST TOLERANCE 20%
J 0
(-1175 2075);
DISPLAY 0.489362 (-1175 2075);
PAINT SKYBLUE (-1175 2075);
FORCEPROP 1 LAST VALUE 22UF
J 0
(-1175 2175);
DISPLAY 0.489362 (-1175 2175);
PAINT SKYBLUE (-1175 2175);
FORCEPROP 1 LAST PART_NUMBER CH622KMEB02
J 0
(-1175 1975);
DISPLAY 0.489362 (-1175 1975);
PAINT SKYBLUE (-1175 1975);
FORCEPROP 1 LAST VOLTAGE 4V
J 0
(-1175 2125);
DISPLAY 0.489362 (-1175 2125);
PAINT SKYBLUE (-1175 2125);
FORCEPROP 1 LAST PACK_TYPE C0402
J 0
(-1175 1925);
DISPLAY 0.489362 (-1175 1925);
PAINT SKYBLUE (-1175 1925);
FORCEPROP 2 LAST CDS_LIB pure_quanta
J 0
(-1225 2125);
PAINT MONO (-1225 2125);
DISPLAY INVISIBLE (-1225 2125);
FORCEPROP 1 LAST PATH I90
J 0
(-1175 2275);
DISPLAY 0.978723 (-1175 2275);
PAINT WHITE (-1175 2275);
DISPLAY INVISIBLE (-1175 2275);
FORCEADD Q_CAP..1
(-1675 2925);
FORCEPROP 1 LAST LOCATION C2394
J 0
(-1625 3025);
DISPLAY 0.489362 (-1625 3025);
PAINT SKYBLUE (-1625 3025);
FORCEPROP 2 LAST $SEC 1
J 0
(-1625 3125);
DISPLAY 0.680851 (-1625 3125);
PAINT MONO (-1625 3125);
DISPLAY INVISIBLE (-1625 3125);
FORCEPROP 2 LAST CDS_SEC 1
J 0
(-1625 3125);
DISPLAY 1.021277 (-1625 3125);
DISPLAY INVISIBLE (-1625 3125);
FORCEPROP 1 LASTPIN (-1675 3025) $PN 1
J 0
(-1665 3005);
DISPLAY 0.489362 (-1665 3005);
FORCEPROP 1 LASTPIN (-1675 2825) $PN 2
J 0
(-1665 2805);
DISPLAY 0.489362 (-1665 2805);
FORCEPROP 1 LAST MATERIAL X6S
J 0
(-1625 2825);
DISPLAY 0.489362 (-1625 2825);
PAINT SKYBLUE (-1625 2825);
FORCEPROP 1 LAST TOLERANCE 20%
J 0
(-1625 2875);
DISPLAY 0.489362 (-1625 2875);
PAINT SKYBLUE (-1625 2875);
FORCEPROP 1 LAST VALUE 22UF
J 0
(-1625 2975);
DISPLAY 0.489362 (-1625 2975);
PAINT SKYBLUE (-1625 2975);
FORCEPROP 1 LAST PART_NUMBER CH622KMEB02
J 0
(-1625 2775);
DISPLAY 0.489362 (-1625 2775);
PAINT SKYBLUE (-1625 2775);
FORCEPROP 1 LAST VOLTAGE 4V
J 0
(-1625 2925);
DISPLAY 0.489362 (-1625 2925);
PAINT SKYBLUE (-1625 2925);
FORCEPROP 1 LAST PACK_TYPE C0402
J 0
(-1625 2725);
DISPLAY 0.489362 (-1625 2725);
PAINT SKYBLUE (-1625 2725);
FORCEPROP 2 LAST CDS_LIB pure_quanta
J 0
(-1675 2925);
PAINT MONO (-1675 2925);
DISPLAY INVISIBLE (-1675 2925);
FORCEPROP 1 LAST PATH I91
J 0
(-1625 3075);
DISPLAY 0.978723 (-1625 3075);
PAINT WHITE (-1625 3075);
DISPLAY INVISIBLE (-1625 3075);
FORCEADD Q_CAP..1
(-1675 3725);
FORCEPROP 1 LAST LOCATION C2393
J 0
(-1625 3825);
DISPLAY 0.489362 (-1625 3825);
PAINT SKYBLUE (-1625 3825);
FORCEPROP 2 LAST $SEC 1
J 0
(-1625 3925);
DISPLAY 0.680851 (-1625 3925);
PAINT MONO (-1625 3925);
DISPLAY INVISIBLE (-1625 3925);
FORCEPROP 2 LAST CDS_SEC 1
J 0
(-1625 3925);
DISPLAY 1.021277 (-1625 3925);
DISPLAY INVISIBLE (-1625 3925);
FORCEPROP 1 LASTPIN (-1675 3825) $PN 1
J 0
(-1665 3805);
DISPLAY 0.489362 (-1665 3805);
FORCEPROP 1 LASTPIN (-1675 3625) $PN 2
J 0
(-1665 3605);
DISPLAY 0.489362 (-1665 3605);
FORCEPROP 1 LAST MATERIAL X6S
J 0
(-1625 3625);
DISPLAY 0.489362 (-1625 3625);
PAINT SKYBLUE (-1625 3625);
FORCEPROP 1 LAST TOLERANCE 20%
J 0
(-1625 3675);
DISPLAY 0.489362 (-1625 3675);
PAINT SKYBLUE (-1625 3675);
FORCEPROP 1 LAST VALUE 22UF
J 0
(-1625 3775);
DISPLAY 0.489362 (-1625 3775);
PAINT SKYBLUE (-1625 3775);
FORCEPROP 1 LAST PART_NUMBER CH622KMEB02
J 0
(-1625 3575);
DISPLAY 0.489362 (-1625 3575);
PAINT SKYBLUE (-1625 3575);
FORCEPROP 1 LAST VOLTAGE 4V
J 0
(-1625 3725);
DISPLAY 0.489362 (-1625 3725);
PAINT SKYBLUE (-1625 3725);
FORCEPROP 1 LAST PACK_TYPE C0402
J 0
(-1625 3525);
DISPLAY 0.489362 (-1625 3525);
PAINT SKYBLUE (-1625 3525);
FORCEPROP 2 LAST CDS_LIB pure_quanta
J 0
(-1675 3725);
PAINT MONO (-1675 3725);
DISPLAY INVISIBLE (-1675 3725);
FORCEPROP 1 LAST PATH I92
J 0
(-1625 3875);
DISPLAY 0.978723 (-1625 3875);
PAINT WHITE (-1625 3875);
DISPLAY INVISIBLE (-1625 3875);
FORCEADD Q_CAP..1
(-1225 2925);
FORCEPROP 1 LAST LOCATION C2399
J 0
(-1175 3025);
DISPLAY 0.489362 (-1175 3025);
PAINT SKYBLUE (-1175 3025);
FORCEPROP 2 LAST $SEC 1
J 0
(-1175 3125);
DISPLAY 0.680851 (-1175 3125);
PAINT MONO (-1175 3125);
DISPLAY INVISIBLE (-1175 3125);
FORCEPROP 2 LAST CDS_SEC 1
J 0
(-1175 3125);
DISPLAY 1.021277 (-1175 3125);
DISPLAY INVISIBLE (-1175 3125);
FORCEPROP 1 LASTPIN (-1225 3025) $PN 1
J 0
(-1215 3005);
DISPLAY 0.489362 (-1215 3005);
FORCEPROP 1 LASTPIN (-1225 2825) $PN 2
J 0
(-1215 2805);
DISPLAY 0.489362 (-1215 2805);
FORCEPROP 1 LAST MATERIAL X6S
J 0
(-1175 2825);
DISPLAY 0.489362 (-1175 2825);
PAINT SKYBLUE (-1175 2825);
FORCEPROP 1 LAST TOLERANCE 20%
J 0
(-1175 2875);
DISPLAY 0.489362 (-1175 2875);
PAINT SKYBLUE (-1175 2875);
FORCEPROP 1 LAST VALUE 22UF
J 0
(-1175 2975);
DISPLAY 0.489362 (-1175 2975);
PAINT SKYBLUE (-1175 2975);
FORCEPROP 1 LAST PART_NUMBER CH622KMEB02
J 0
(-1175 2775);
DISPLAY 0.489362 (-1175 2775);
PAINT SKYBLUE (-1175 2775);
FORCEPROP 1 LAST VOLTAGE 4V
J 0
(-1175 2925);
DISPLAY 0.489362 (-1175 2925);
PAINT SKYBLUE (-1175 2925);
FORCEPROP 1 LAST PACK_TYPE C0402
J 0
(-1175 2725);
DISPLAY 0.489362 (-1175 2725);
PAINT SKYBLUE (-1175 2725);
FORCEPROP 2 LAST CDS_LIB pure_quanta
J 0
(-1225 2925);
PAINT MONO (-1225 2925);
DISPLAY INVISIBLE (-1225 2925);
FORCEPROP 1 LAST PATH I93
J 0
(-1175 3075);
DISPLAY 0.978723 (-1175 3075);
PAINT WHITE (-1175 3075);
DISPLAY INVISIBLE (-1175 3075);
FORCEADD Q_CAP..1
(-1225 3725);
FORCEPROP 1 LAST LOCATION C2398
J 0
(-1175 3825);
DISPLAY 0.489362 (-1175 3825);
PAINT SKYBLUE (-1175 3825);
FORCEPROP 2 LAST $SEC 1
J 0
(-1175 3925);
DISPLAY 0.680851 (-1175 3925);
PAINT MONO (-1175 3925);
DISPLAY INVISIBLE (-1175 3925);
FORCEPROP 2 LAST CDS_SEC 1
J 0
(-1175 3925);
DISPLAY 1.021277 (-1175 3925);
DISPLAY INVISIBLE (-1175 3925);
FORCEPROP 1 LASTPIN (-1225 3825) $PN 1
J 0
(-1215 3805);
DISPLAY 0.489362 (-1215 3805);
FORCEPROP 1 LASTPIN (-1225 3625) $PN 2
J 0
(-1215 3605);
DISPLAY 0.489362 (-1215 3605);
FORCEPROP 1 LAST MATERIAL X6S
J 0
(-1175 3625);
DISPLAY 0.489362 (-1175 3625);
PAINT SKYBLUE (-1175 3625);
FORCEPROP 1 LAST TOLERANCE 20%
J 0
(-1175 3675);
DISPLAY 0.489362 (-1175 3675);
PAINT SKYBLUE (-1175 3675);
FORCEPROP 1 LAST VALUE 22UF
J 0
(-1175 3775);
DISPLAY 0.489362 (-1175 3775);
PAINT SKYBLUE (-1175 3775);
FORCEPROP 1 LAST PART_NUMBER CH622KMEB02
J 0
(-1175 3575);
DISPLAY 0.489362 (-1175 3575);
PAINT SKYBLUE (-1175 3575);
FORCEPROP 1 LAST VOLTAGE 4V
J 0
(-1175 3725);
DISPLAY 0.489362 (-1175 3725);
PAINT SKYBLUE (-1175 3725);
FORCEPROP 1 LAST PACK_TYPE C0402
J 0
(-1175 3525);
DISPLAY 0.489362 (-1175 3525);
PAINT SKYBLUE (-1175 3525);
FORCEPROP 2 LAST CDS_LIB pure_quanta
J 0
(-1225 3725);
PAINT MONO (-1225 3725);
DISPLAY INVISIBLE (-1225 3725);
FORCEPROP 1 LAST PATH I94
J 0
(-1175 3875);
DISPLAY 0.978723 (-1175 3875);
PAINT WHITE (-1175 3875);
DISPLAY INVISIBLE (-1175 3875);
FORCEADD UNIVERSAL_GND..1
(-825 1750);
FORCEPROP 3 LASTPIN (-825 1800) SIG_NAME GND\g
J 0
(-815 1810);
DISPLAY 0.659574 (-815 1810);
PAINT MONO (-815 1810);
DISPLAY INVISIBLE (-815 1810);
FORCEPROP 2 LAST CDS_LIB pure_quanta_power
J 0
(-825 1750);
PAINT MONO (-825 1750);
DISPLAY INVISIBLE (-825 1750);
FORCEPROP 1 LAST PATH I95
J 0
(-750 1750);
DISPLAY 0.872340 (-750 1750);
PAINT AQUA (-750 1750);
DISPLAY INVISIBLE (-750 1750);
FORCEPROP 1 LAST HDL_POWER GND
J 1
(-800 1675);
DISPLAY 0.872340 (-800 1675);
PAINT GREEN (-800 1675);
DISPLAY INVISIBLE (-800 1675);
FORCEADD Q_CAP..1
(-825 2125);
FORCEPROP 1 LAST LOCATION C2405
J 0
(-775 2225);
DISPLAY 0.489362 (-775 2225);
PAINT SKYBLUE (-775 2225);
FORCEPROP 2 LAST $SEC 1
J 0
(-775 2325);
DISPLAY 0.680851 (-775 2325);
PAINT MONO (-775 2325);
DISPLAY INVISIBLE (-775 2325);
FORCEPROP 2 LAST CDS_SEC 1
J 0
(-775 2325);
DISPLAY 1.021277 (-775 2325);
DISPLAY INVISIBLE (-775 2325);
FORCEPROP 1 LASTPIN (-825 2225) $PN 1
J 0
(-815 2205);
DISPLAY 0.489362 (-815 2205);
FORCEPROP 1 LASTPIN (-825 2025) $PN 2
J 0
(-815 2005);
DISPLAY 0.489362 (-815 2005);
FORCEPROP 1 LAST MATERIAL X6S
J 0
(-775 2025);
DISPLAY 0.489362 (-775 2025);
PAINT SKYBLUE (-775 2025);
FORCEPROP 1 LAST TOLERANCE 20%
J 0
(-775 2075);
DISPLAY 0.489362 (-775 2075);
PAINT SKYBLUE (-775 2075);
FORCEPROP 1 LAST VALUE 22UF
J 0
(-775 2175);
DISPLAY 0.489362 (-775 2175);
PAINT SKYBLUE (-775 2175);
FORCEPROP 1 LAST PART_NUMBER CH622KMEB02
J 0
(-775 1975);
DISPLAY 0.489362 (-775 1975);
PAINT SKYBLUE (-775 1975);
FORCEPROP 1 LAST VOLTAGE 4V
J 0
(-775 2125);
DISPLAY 0.489362 (-775 2125);
PAINT SKYBLUE (-775 2125);
FORCEPROP 1 LAST PACK_TYPE C0402
J 0
(-775 1925);
DISPLAY 0.489362 (-775 1925);
PAINT SKYBLUE (-775 1925);
FORCEPROP 2 LAST CDS_LIB pure_quanta
J 0
(-825 2125);
PAINT MONO (-825 2125);
DISPLAY INVISIBLE (-825 2125);
FORCEPROP 1 LAST PATH I96
J 0
(-775 2275);
DISPLAY 0.978723 (-775 2275);
PAINT WHITE (-775 2275);
DISPLAY INVISIBLE (-775 2275);
FORCEADD UNIVERSAL_GND..1
(-825 2550);
FORCEPROP 3 LASTPIN (-825 2600) SIG_NAME GND\g
J 0
(-815 2610);
DISPLAY 0.659574 (-815 2610);
PAINT MONO (-815 2610);
DISPLAY INVISIBLE (-815 2610);
FORCEPROP 2 LAST CDS_LIB pure_quanta_power
J 0
(-825 2550);
PAINT MONO (-825 2550);
DISPLAY INVISIBLE (-825 2550);
FORCEPROP 1 LAST PATH I97
J 0
(-750 2550);
DISPLAY 0.872340 (-750 2550);
PAINT AQUA (-750 2550);
DISPLAY INVISIBLE (-750 2550);
FORCEPROP 1 LAST HDL_POWER GND
J 1
(-800 2475);
DISPLAY 0.872340 (-800 2475);
PAINT GREEN (-800 2475);
DISPLAY INVISIBLE (-800 2475);
FORCEADD Q_CAP..1
(-825 2925);
FORCEPROP 1 LAST LOCATION C2404
J 0
(-775 3025);
DISPLAY 0.489362 (-775 3025);
PAINT SKYBLUE (-775 3025);
FORCEPROP 2 LAST $SEC 1
J 0
(-775 3125);
DISPLAY 0.680851 (-775 3125);
PAINT MONO (-775 3125);
DISPLAY INVISIBLE (-775 3125);
FORCEPROP 2 LAST CDS_SEC 1
J 0
(-775 3125);
DISPLAY 1.021277 (-775 3125);
DISPLAY INVISIBLE (-775 3125);
FORCEPROP 1 LASTPIN (-825 3025) $PN 1
J 0
(-815 3005);
DISPLAY 0.489362 (-815 3005);
FORCEPROP 1 LASTPIN (-825 2825) $PN 2
J 0
(-815 2805);
DISPLAY 0.489362 (-815 2805);
FORCEPROP 1 LAST MATERIAL X6S
J 0
(-775 2825);
DISPLAY 0.489362 (-775 2825);
PAINT SKYBLUE (-775 2825);
FORCEPROP 1 LAST TOLERANCE 20%
J 0
(-775 2875);
DISPLAY 0.489362 (-775 2875);
PAINT SKYBLUE (-775 2875);
FORCEPROP 1 LAST VALUE 22UF
J 0
(-775 2975);
DISPLAY 0.489362 (-775 2975);
PAINT SKYBLUE (-775 2975);
FORCEPROP 1 LAST PART_NUMBER CH622KMEB02
J 0
(-775 2775);
DISPLAY 0.489362 (-775 2775);
PAINT SKYBLUE (-775 2775);
FORCEPROP 1 LAST VOLTAGE 4V
J 0
(-775 2925);
DISPLAY 0.489362 (-775 2925);
PAINT SKYBLUE (-775 2925);
FORCEPROP 1 LAST PACK_TYPE C0402
J 0
(-775 2725);
DISPLAY 0.489362 (-775 2725);
PAINT SKYBLUE (-775 2725);
FORCEPROP 2 LAST CDS_LIB pure_quanta
J 0
(-825 2925);
PAINT MONO (-825 2925);
DISPLAY INVISIBLE (-825 2925);
FORCEPROP 1 LAST PATH I98
J 0
(-775 3075);
DISPLAY 0.978723 (-775 3075);
PAINT WHITE (-775 3075);
DISPLAY INVISIBLE (-775 3075);
FORCEADD UNIVERSAL_GND..1
(-825 3350);
FORCEPROP 3 LASTPIN (-825 3400) SIG_NAME GND\g
J 0
(-815 3410);
DISPLAY 0.659574 (-815 3410);
PAINT MONO (-815 3410);
DISPLAY INVISIBLE (-815 3410);
FORCEPROP 2 LAST CDS_LIB pure_quanta_power
J 0
(-825 3350);
PAINT MONO (-825 3350);
DISPLAY INVISIBLE (-825 3350);
FORCEPROP 1 LAST PATH I99
J 0
(-750 3350);
DISPLAY 0.872340 (-750 3350);
PAINT AQUA (-750 3350);
DISPLAY INVISIBLE (-750 3350);
FORCEPROP 1 LAST HDL_POWER GND
J 1
(-800 3275);
DISPLAY 0.872340 (-800 3275);
PAINT GREEN (-800 3275);
DISPLAY INVISIBLE (-800 3275);
FORCEADD QUANTA_TITLE_BLOCK_C..1
(-400 -525);
FORCEPROP 0 LAST CDS_CON_LAST_MODIFIED Fri Mar 11 14:52:46 2022
J 0
(-2285 -510);
DISPLAY INVISIBLE (-2285 -510);
FORCEPROP 1 LAST CUSTOM_TXT_CDS <CON_LAST_MODIFIED>
J 0
(-2285 -510);
DISPLAY 0.978723 (-2285 -510);
FORCEPROP 2 LAST CUSTOM_TXT_CDS <XR_PAGE_TITLE>
J 0
(-8290 4725);
DISPLAY 0.638298 (-8290 4725);
PAINT PINK (-8290 4725);
DISPLAY INVISIBLE (-8290 4725);
FORCEPROP 1 LAST CUSTOM_TXT_CDS <NAME_2>
J 0
(-3575 -475);
FORCEPROP 1 LAST CUSTOM_TXT_CDS <NAME_1>
J 0
(-3575 -350);
FORCEPROP 1 LAST CUSTOM_TXT_CDS <Q_NUMBER>
J 0
(-1803 -422);
DISPLAY 1.212766 (-1803 -422);
FORCEPROP 1 LAST CUSTOM_TXT_CDS <Q_PROJ>
J 0
(-2782 -423);
DISPLAY 1.212766 (-2782 -423);
FORCEPROP 1 LAST CUSTOM_TXT_CDS <Q_REV>
J 0
(-584 -422);
DISPLAY 1.212766 (-584 -422);
FORCEPROP 1 LAST CUSTOM_TXT_CDS <CON_PAGE_NUM> OF <CON_TOTAL_PAGES>
J 0
(-846 -507);
DISPLAY 0.978723 (-846 -507);
FORCEPROP 1 LAST Q_TITLE CPU1 CAVITY BOT DECOUPLING CAPS 1/3
J 0
(-9766 -499);
DISPLAY 2.446809 (-9766 -499);
PAINT GREEN (-9766 -499);
FORCEPROP 1 LAST Q_DEPT BU9
J 1
(-4163 -476);
DISPLAY 1.957447 (-4163 -476);
PAINT GREEN (-4163 -476);
FORCEPROP 2 LAST PAGE_BORDER TRUE
J 0
(-8290 4725);
DISPLAY 0.638298 (-8290 4725);
PAINT PINK (-8290 4725);
DISPLAY INVISIBLE (-8290 4725);
FORCEPROP 1 LAST CDS_LMAN_SYM_OUTLINE -9475,6775,100,-125
J 0
(-400 -525);
DISPLAY 0.468085 (-400 -525);
PAINT GREEN (-400 -525);
DISPLAY INVISIBLE (-400 -525);
FORCEPROP 2 LAST CDS_LIB pure_quanta
J 0
(-400 -525);
DISPLAY INVISIBLE (-400 -525);
FORCEPROP 1 LAST COMMENT_BODY TRUE
J 0
(-388 -538);
DISPLAY 0.978723 (-388 -538);
PAINT GREEN (-388 -538);
DISPLAY INVISIBLE (-388 -538);
FORCEPROP 2 LAST CDS_XR_PAGE_TITLE CR-72 : @T6G_MB_LIB.T6G(SCH_1):PAGE72
J 0
(-8290 4725);
DISPLAY 0.638298 (-8290 4725);
PAINT PINK (-8290 4725);
DISPLAY INVISIBLE (-8290 4725);
WIRE 16 -1 (-8950 1900)(-9400 1900);
WIRE 16 -1 (-8500 1900)(-8950 1900);
WIRE 16 -1 (-8950 1900)(-8950 2025);
WIRE 16 -1 (-9400 1900)(-9400 2025);
WIRE 16 -1 (-8050 1900)(-8500 1900);
WIRE 16 -1 (-8500 1900)(-8500 2025);
WIRE 16 -1 (-7600 1900)(-8050 1900);
WIRE 16 -1 (-8050 1900)(-8050 2025);
WIRE 16 -1 (-7150 1900)(-7600 1900);
WIRE 16 -1 (-7600 1900)(-7600 2025);
WIRE 16 -1 (-6700 1900)(-7150 1900);
WIRE 16 -1 (-7150 1900)(-7150 2025);
WIRE 16 -1 (-6250 1900)(-6700 1900);
WIRE 16 -1 (-6700 1900)(-6700 2025);
WIRE 16 -1 (-5800 1900)(-6250 1900);
WIRE 16 -1 (-6250 1900)(-6250 2025);
WIRE 16 -1 (-5800 1900)(-5400 1900);
WIRE 16 -1 (-5800 1900)(-5800 2025);
WIRE 16 -1 (-5400 1800)(-5400 1900);
WIRE 16 -1 (-5400 1900)(-5400 2025);
WIRE 16 -1 (-8950 1500)(-9400 1500);
WIRE 16 -1 (-8500 1500)(-8950 1500);
WIRE 16 -1 (-8950 1425)(-8950 1500);
WIRE 16 -1 (-9400 1500)(-9400 1550);
WIRE 16 -1 (-9400 1500)(-9400 1425);
WIRE 16 -1 (-8050 1500)(-8500 1500);
WIRE 16 -1 (-8500 1500)(-8500 1425);
WIRE 16 -1 (-7600 1500)(-8050 1500);
WIRE 16 -1 (-8050 1425)(-8050 1500);
WIRE 16 -1 (-7600 1425)(-7600 1500);
WIRE 16 -1 (-8950 1100)(-9400 1100);
WIRE 16 -1 (-8500 1100)(-8950 1100);
WIRE 16 -1 (-8950 1100)(-8950 1225);
WIRE 16 -1 (-9400 1100)(-9400 1225);
WIRE 16 -1 (-8050 1100)(-8500 1100);
WIRE 16 -1 (-8500 1100)(-8500 1225);
WIRE 16 -1 (-7600 1100)(-8050 1100);
WIRE 16 -1 (-8050 1100)(-8050 1225);
WIRE 16 -1 (-7600 1000)(-7600 1100);
WIRE 16 -1 (-7600 1100)(-7600 1225);
WIRE 16 -1 (-5400 2225)(-5400 2300);
WIRE 16 -1 (-5400 2300)(-5800 2300);
WIRE 16 -1 (-5800 2300)(-5800 2225);
WIRE 16 -1 (-5800 2300)(-6250 2300);
WIRE 16 -1 (-6250 2225)(-6250 2300);
WIRE 16 -1 (-6250 2300)(-6700 2300);
WIRE 16 -1 (-6700 2225)(-6700 2300);
WIRE 16 -1 (-6700 2300)(-7150 2300);
WIRE 16 -1 (-7150 2300)(-7150 2225);
WIRE 16 -1 (-7150 2300)(-7600 2300);
WIRE 16 -1 (-7600 2225)(-7600 2300);
WIRE 16 -1 (-7600 2300)(-8050 2300);
WIRE 16 -1 (-8050 2225)(-8050 2300);
WIRE 16 -1 (-8050 2300)(-8500 2300);
WIRE 16 -1 (-8500 2300)(-8500 2225);
WIRE 16 -1 (-8500 2300)(-8950 2300);
WIRE 16 -1 (-8950 2300)(-9400 2300);
WIRE 16 -1 (-8950 2225)(-8950 2300);
WIRE 16 -1 (-9400 2300)(-9400 2350);
WIRE 16 -1 (-9400 2300)(-9400 2225);
WIRE 16 -1 (-5400 3025)(-5400 3100);
WIRE 16 -1 (-5400 3100)(-5800 3100);
WIRE 16 -1 (-5800 3100)(-5800 3025);
WIRE 16 -1 (-5800 3100)(-6250 3100);
WIRE 16 -1 (-6250 3025)(-6250 3100);
WIRE 16 -1 (-6250 3100)(-6700 3100);
WIRE 16 -1 (-6700 3025)(-6700 3100);
WIRE 16 -1 (-6700 3100)(-7150 3100);
WIRE 16 -1 (-7150 3100)(-7150 3025);
WIRE 16 -1 (-7150 3100)(-7600 3100);
WIRE 16 -1 (-7600 3025)(-7600 3100);
WIRE 16 -1 (-7600 3100)(-8050 3100);
WIRE 16 -1 (-8050 3025)(-8050 3100);
WIRE 16 -1 (-8050 3100)(-8500 3100);
WIRE 16 -1 (-8500 3100)(-8950 3100);
WIRE 16 -1 (-8500 3100)(-8500 3025);
WIRE 16 -1 (-8950 3100)(-9400 3100);
WIRE 16 -1 (-8950 3025)(-8950 3100);
WIRE 16 -1 (-9400 3100)(-9400 3150);
WIRE 16 -1 (-9400 3100)(-9400 3025);
WIRE 16 -1 (-8950 2700)(-9400 2700);
WIRE 16 -1 (-8500 2700)(-8950 2700);
WIRE 16 -1 (-8950 2700)(-8950 2825);
WIRE 16 -1 (-9400 2700)(-9400 2825);
WIRE 16 -1 (-8050 2700)(-8500 2700);
WIRE 16 -1 (-8500 2700)(-8500 2825);
WIRE 16 -1 (-7600 2700)(-8050 2700);
WIRE 16 -1 (-8050 2700)(-8050 2825);
WIRE 16 -1 (-7150 2700)(-7600 2700);
WIRE 16 -1 (-7600 2700)(-7600 2825);
WIRE 16 -1 (-6700 2700)(-7150 2700);
WIRE 16 -1 (-7150 2700)(-7150 2825);
WIRE 16 -1 (-6250 2700)(-6700 2700);
WIRE 16 -1 (-6700 2700)(-6700 2825);
WIRE 16 -1 (-5800 2700)(-6250 2700);
WIRE 16 -1 (-6250 2700)(-6250 2825);
WIRE 16 -1 (-5800 2700)(-5400 2700);
WIRE 16 -1 (-5800 2700)(-5800 2825);
WIRE 16 -1 (-5400 2700)(-5400 2825);
WIRE 16 -1 (-5400 2600)(-5400 2700);
WIRE 16 -1 (-5400 3825)(-5400 3900);
WIRE 16 -1 (-5400 3900)(-5800 3900);
WIRE 16 -1 (-5800 3900)(-5800 3825);
WIRE 16 -1 (-5800 3900)(-6250 3900);
WIRE 16 -1 (-6250 3825)(-6250 3900);
WIRE 16 -1 (-6250 3900)(-6700 3900);
WIRE 16 -1 (-6700 3825)(-6700 3900);
WIRE 16 -1 (-6700 3900)(-7150 3900);
WIRE 16 -1 (-7150 3900)(-7150 3825);
WIRE 16 -1 (-7150 3900)(-7600 3900);
WIRE 16 -1 (-7600 3825)(-7600 3900);
WIRE 16 -1 (-7600 3900)(-8050 3900);
WIRE 16 -1 (-8050 3825)(-8050 3900);
WIRE 16 -1 (-8050 3900)(-8500 3900);
WIRE 16 -1 (-8500 3900)(-8500 3825);
WIRE 16 -1 (-8500 3900)(-8950 3900);
WIRE 16 -1 (-8950 3900)(-9400 3900);
WIRE 16 -1 (-8950 3825)(-8950 3900);
WIRE 16 -1 (-9400 3900)(-9400 3950);
WIRE 16 -1 (-9400 3900)(-9400 3825);
WIRE 16 -1 (-8950 3500)(-9400 3500);
WIRE 16 -1 (-8500 3500)(-8950 3500);
WIRE 16 -1 (-8950 3500)(-8950 3625);
WIRE 16 -1 (-9400 3500)(-9400 3625);
WIRE 16 -1 (-8050 3500)(-8500 3500);
WIRE 16 -1 (-8500 3500)(-8500 3625);
WIRE 16 -1 (-7600 3500)(-8050 3500);
WIRE 16 -1 (-8050 3500)(-8050 3625);
WIRE 16 -1 (-7150 3500)(-7600 3500);
WIRE 16 -1 (-7600 3500)(-7600 3625);
WIRE 16 -1 (-7150 3500)(-7150 3625);
WIRE 16 -1 (-6700 3500)(-7150 3500);
WIRE 16 -1 (-6250 3500)(-6700 3500);
WIRE 16 -1 (-6700 3500)(-6700 3625);
WIRE 16 -1 (-5800 3500)(-6250 3500);
WIRE 16 -1 (-6250 3500)(-6250 3625);
WIRE 16 -1 (-5800 3500)(-5400 3500);
WIRE 16 -1 (-5800 3500)(-5800 3625);
WIRE 16 -1 (-5400 3500)(-5400 3625);
WIRE 16 -1 (-5400 3400)(-5400 3500);
WIRE 16 -1 (-5400 4600)(-5400 4675);
WIRE 16 -1 (-5400 4675)(-5800 4675);
WIRE 16 -1 (-5800 4675)(-5800 4600);
WIRE 16 -1 (-5800 4675)(-6250 4675);
WIRE 16 -1 (-6250 4600)(-6250 4675);
WIRE 16 -1 (-6250 4675)(-6700 4675);
WIRE 16 -1 (-6700 4600)(-6700 4675);
WIRE 16 -1 (-6700 4675)(-7150 4675);
WIRE 16 -1 (-7150 4675)(-7150 4600);
WIRE 16 -1 (-7150 4675)(-7600 4675);
WIRE 16 -1 (-7600 4600)(-7600 4675);
WIRE 16 -1 (-7600 4675)(-8050 4675);
WIRE 16 -1 (-8050 4600)(-8050 4675);
WIRE 16 -1 (-8050 4675)(-8500 4675);
WIRE 16 -1 (-8500 4675)(-8500 4600);
WIRE 16 -1 (-8500 4675)(-8950 4675);
WIRE 16 -1 (-8950 4675)(-9400 4675);
WIRE 16 -1 (-8950 4600)(-8950 4675);
WIRE 16 -1 (-9400 4675)(-9400 4725);
WIRE 16 -1 (-9400 4675)(-9400 4600);
WIRE 16 -1 (-8950 4275)(-9400 4275);
WIRE 16 -1 (-8500 4275)(-8950 4275);
WIRE 16 -1 (-8950 4275)(-8950 4400);
WIRE 16 -1 (-9400 4275)(-9400 4400);
WIRE 16 -1 (-8050 4275)(-8500 4275);
WIRE 16 -1 (-8500 4275)(-8500 4400);
WIRE 16 -1 (-7600 4275)(-8050 4275);
WIRE 16 -1 (-8050 4275)(-8050 4400);
WIRE 16 -1 (-7150 4275)(-7600 4275);
WIRE 16 -1 (-7600 4275)(-7600 4400);
WIRE 16 -1 (-6700 4275)(-7150 4275);
WIRE 16 -1 (-7150 4275)(-7150 4400);
WIRE 16 -1 (-6250 4275)(-6700 4275);
WIRE 16 -1 (-6700 4275)(-6700 4400);
WIRE 16 -1 (-5800 4275)(-6250 4275);
WIRE 16 -1 (-6250 4275)(-6250 4400);
WIRE 16 -1 (-5400 4275)(-5800 4275);
WIRE 16 -1 (-5800 4275)(-5800 4400);
WIRE 16 -1 (-5400 4275)(-5400 4400);
WIRE 16 -1 (-5400 4175)(-5400 4275);
WIRE 16 3135 (-9625 600)(-5100 600);
WIRE 16 3135 (-9625 600)(-9625 5350);
WIRE 16 3135 (-5100 600)(-5100 5350);
WIRE 16 3135 (-9625 5350)(-5100 5350);
WIRE 16 -1 (-4375 1900)(-4825 1900);
WIRE 16 -1 (-3925 1900)(-4375 1900);
WIRE 16 -1 (-4375 1900)(-4375 2025);
WIRE 16 -1 (-4825 1900)(-4825 2025);
WIRE 16 -1 (-3475 1900)(-3925 1900);
WIRE 16 -1 (-3925 1900)(-3925 2025);
WIRE 16 -1 (-3025 1900)(-3475 1900);
WIRE 16 -1 (-3475 1900)(-3475 2025);
WIRE 16 -1 (-2575 1900)(-3025 1900);
WIRE 16 -1 (-3025 1900)(-3025 2025);
WIRE 16 -1 (-2125 1900)(-2575 1900);
WIRE 16 -1 (-2575 1900)(-2575 2025);
WIRE 16 -1 (-1675 1900)(-2125 1900);
WIRE 16 -1 (-2125 1900)(-2125 2025);
WIRE 16 -1 (-1225 1900)(-1675 1900);
WIRE 16 -1 (-1675 1900)(-1675 2025);
WIRE 16 -1 (-1225 1900)(-825 1900);
WIRE 16 -1 (-1225 1900)(-1225 2025);
WIRE 16 -1 (-825 1800)(-825 1900);
WIRE 16 -1 (-825 1900)(-825 2025);
WIRE 16 -1 (-4375 1500)(-4825 1500);
WIRE 16 -1 (-3925 1500)(-4375 1500);
WIRE 16 -1 (-4375 1425)(-4375 1500);
WIRE 16 -1 (-4825 1500)(-4825 1550);
WIRE 16 -1 (-4825 1500)(-4825 1425);
WIRE 16 -1 (-3475 1500)(-3925 1500);
WIRE 16 -1 (-3925 1500)(-3925 1425);
WIRE 16 -1 (-3025 1500)(-3475 1500);
WIRE 16 -1 (-3475 1425)(-3475 1500);
WIRE 16 -1 (-3025 1425)(-3025 1500);
WIRE 16 -1 (-4375 1100)(-4825 1100);
WIRE 16 -1 (-3925 1100)(-4375 1100);
WIRE 16 -1 (-4375 1100)(-4375 1225);
WIRE 16 -1 (-4825 1100)(-4825 1225);
WIRE 16 -1 (-3475 1100)(-3925 1100);
WIRE 16 -1 (-3925 1100)(-3925 1225);
WIRE 16 -1 (-3025 1100)(-3475 1100);
WIRE 16 -1 (-3475 1100)(-3475 1225);
WIRE 16 -1 (-3025 1100)(-3025 1225);
WIRE 16 -1 (-3025 1000)(-3025 1100);
WIRE 16 -1 (-4375 2700)(-4825 2700);
WIRE 16 -1 (-3925 2700)(-4375 2700);
WIRE 16 -1 (-4375 2700)(-4375 2825);
WIRE 16 -1 (-4825 2700)(-4825 2825);
WIRE 16 -1 (-3475 2700)(-3925 2700);
WIRE 16 -1 (-3925 2700)(-3925 2825);
WIRE 16 -1 (-3025 2700)(-3475 2700);
WIRE 16 -1 (-3475 2700)(-3475 2825);
WIRE 16 -1 (-2575 2700)(-3025 2700);
WIRE 16 -1 (-3025 2700)(-3025 2825);
WIRE 16 -1 (-2125 2700)(-2575 2700);
WIRE 16 -1 (-2575 2700)(-2575 2825);
WIRE 16 -1 (-1675 2700)(-2125 2700);
WIRE 16 -1 (-2125 2700)(-2125 2825);
WIRE 16 -1 (-1225 2700)(-1675 2700);
WIRE 16 -1 (-1675 2700)(-1675 2825);
WIRE 16 -1 (-1225 2700)(-825 2700);
WIRE 16 -1 (-1225 2700)(-1225 2825);
WIRE 16 -1 (-825 2700)(-825 2825);
WIRE 16 -1 (-825 2600)(-825 2700);
WIRE 16 -1 (-825 2225)(-825 2300);
WIRE 16 -1 (-825 2300)(-1225 2300);
WIRE 16 -1 (-1225 2300)(-1225 2225);
WIRE 16 -1 (-1225 2300)(-1675 2300);
WIRE 16 -1 (-1675 2225)(-1675 2300);
WIRE 16 -1 (-1675 2300)(-2125 2300);
WIRE 16 -1 (-2125 2225)(-2125 2300);
WIRE 16 -1 (-2125 2300)(-2575 2300);
WIRE 16 -1 (-2575 2300)(-2575 2225);
WIRE 16 -1 (-2575 2300)(-3025 2300);
WIRE 16 -1 (-3025 2225)(-3025 2300);
WIRE 16 -1 (-3025 2300)(-3475 2300);
WIRE 16 -1 (-3475 2225)(-3475 2300);
WIRE 16 -1 (-3475 2300)(-3925 2300);
WIRE 16 -1 (-3925 2300)(-3925 2225);
WIRE 16 -1 (-3925 2300)(-4375 2300);
WIRE 16 -1 (-4375 2300)(-4825 2300);
WIRE 16 -1 (-4375 2225)(-4375 2300);
WIRE 16 -1 (-4825 2300)(-4825 2350);
WIRE 16 -1 (-4825 2300)(-4825 2225);
WIRE 16 -1 (-825 3825)(-825 3900);
WIRE 16 -1 (-825 3900)(-1225 3900);
WIRE 16 -1 (-1225 3900)(-1225 3825);
WIRE 16 -1 (-1225 3900)(-1675 3900);
WIRE 16 -1 (-1675 3825)(-1675 3900);
WIRE 16 -1 (-1675 3900)(-2125 3900);
WIRE 16 -1 (-2125 3825)(-2125 3900);
WIRE 16 -1 (-2125 3900)(-2575 3900);
WIRE 16 -1 (-2575 3900)(-2575 3825);
WIRE 16 -1 (-2575 3900)(-3025 3900);
WIRE 16 -1 (-3025 3825)(-3025 3900);
WIRE 16 -1 (-3025 3900)(-3475 3900);
WIRE 16 -1 (-3475 3825)(-3475 3900);
WIRE 16 -1 (-3475 3900)(-3925 3900);
WIRE 16 -1 (-3925 3900)(-3925 3825);
WIRE 16 -1 (-3925 3900)(-4375 3900);
WIRE 16 -1 (-4375 3900)(-4825 3900);
WIRE 16 -1 (-4375 3825)(-4375 3900);
WIRE 16 -1 (-4825 3900)(-4825 3950);
WIRE 16 -1 (-4825 3900)(-4825 3825);
WIRE 16 -1 (-4375 3500)(-4825 3500);
WIRE 16 -1 (-3925 3500)(-4375 3500);
WIRE 16 -1 (-4375 3500)(-4375 3625);
WIRE 16 -1 (-4825 3500)(-4825 3625);
WIRE 16 -1 (-3475 3500)(-3925 3500);
WIRE 16 -1 (-3925 3500)(-3925 3625);
WIRE 16 -1 (-3025 3500)(-3475 3500);
WIRE 16 -1 (-3475 3500)(-3475 3625);
WIRE 16 -1 (-3025 3500)(-3025 3625);
WIRE 16 -1 (-2575 3500)(-3025 3500);
WIRE 16 -1 (-2125 3500)(-2575 3500);
WIRE 16 -1 (-2575 3500)(-2575 3625);
WIRE 16 -1 (-1675 3500)(-2125 3500);
WIRE 16 -1 (-2125 3500)(-2125 3625);
WIRE 16 -1 (-1225 3500)(-1675 3500);
WIRE 16 -1 (-1675 3500)(-1675 3625);
WIRE 16 -1 (-1225 3500)(-825 3500);
WIRE 16 -1 (-1225 3500)(-1225 3625);
WIRE 16 -1 (-825 3500)(-825 3625);
WIRE 16 -1 (-825 3400)(-825 3500);
WIRE 16 -1 (-4375 3100)(-4825 3100);
WIRE 16 -1 (-4375 3025)(-4375 3100);
WIRE 16 -1 (-3925 3100)(-4375 3100);
WIRE 16 -1 (-4825 3100)(-4825 3150);
WIRE 16 -1 (-4825 3100)(-4825 3025);
WIRE 16 -1 (-3475 3100)(-3925 3100);
WIRE 16 -1 (-3925 3100)(-3925 3025);
WIRE 16 -1 (-3475 3025)(-3475 3100);
WIRE 16 -1 (-3025 3100)(-3475 3100);
WIRE 16 -1 (-2575 3100)(-3025 3100);
WIRE 16 -1 (-3025 3025)(-3025 3100);
WIRE 16 -1 (-2125 3100)(-2575 3100);
WIRE 16 -1 (-2575 3100)(-2575 3025);
WIRE 16 -1 (-2125 3025)(-2125 3100);
WIRE 16 -1 (-1675 3100)(-2125 3100);
WIRE 16 -1 (-1225 3100)(-1675 3100);
WIRE 16 -1 (-1675 3025)(-1675 3100);
WIRE 16 -1 (-825 3100)(-1225 3100);
WIRE 16 -1 (-1225 3100)(-1225 3025);
WIRE 16 -1 (-825 3025)(-825 3100);
WIRE 16 -1 (-825 4600)(-825 4675);
WIRE 16 -1 (-825 4675)(-1225 4675);
WIRE 16 -1 (-1225 4675)(-1225 4600);
WIRE 16 -1 (-1225 4675)(-1675 4675);
WIRE 16 -1 (-1675 4600)(-1675 4675);
WIRE 16 -1 (-1675 4675)(-2125 4675);
WIRE 16 -1 (-2125 4600)(-2125 4675);
WIRE 16 -1 (-2125 4675)(-2575 4675);
WIRE 16 -1 (-2575 4675)(-3025 4675);
WIRE 16 -1 (-2575 4675)(-2575 4600);
WIRE 16 -1 (-3025 4600)(-3025 4675);
WIRE 16 -1 (-3025 4675)(-3475 4675);
WIRE 16 -1 (-3475 4600)(-3475 4675);
WIRE 16 -1 (-3475 4675)(-3925 4675);
WIRE 16 -1 (-3925 4675)(-3925 4600);
WIRE 16 -1 (-3925 4675)(-4375 4675);
WIRE 16 -1 (-4375 4675)(-4825 4675);
WIRE 16 -1 (-4375 4600)(-4375 4675);
WIRE 16 -1 (-4825 4675)(-4825 4725);
WIRE 16 -1 (-4825 4675)(-4825 4600);
WIRE 16 -1 (-4375 4275)(-4825 4275);
WIRE 16 -1 (-3925 4275)(-4375 4275);
WIRE 16 -1 (-4375 4275)(-4375 4400);
WIRE 16 -1 (-4825 4275)(-4825 4400);
WIRE 16 -1 (-3475 4275)(-3925 4275);
WIRE 16 -1 (-3925 4275)(-3925 4400);
WIRE 16 -1 (-3025 4275)(-3475 4275);
WIRE 16 -1 (-3475 4275)(-3475 4400);
WIRE 16 -1 (-2575 4275)(-3025 4275);
WIRE 16 -1 (-3025 4275)(-3025 4400);
WIRE 16 -1 (-2125 4275)(-2575 4275);
WIRE 16 -1 (-2575 4275)(-2575 4400);
WIRE 16 -1 (-1675 4275)(-2125 4275);
WIRE 16 -1 (-2125 4275)(-2125 4400);
WIRE 16 -1 (-1225 4275)(-1675 4275);
WIRE 16 -1 (-1675 4275)(-1675 4400);
WIRE 16 -1 (-825 4275)(-1225 4275);
WIRE 16 -1 (-1225 4275)(-1225 4400);
WIRE 16 -1 (-825 4275)(-825 4400);
WIRE 16 -1 (-825 4175)(-825 4275);
WIRE 16 3135 (-5000 600)(-500 600);
WIRE 16 3135 (-5000 600)(-5000 5350);
WIRE 16 3135 (-500 600)(-500 5350);
WIRE 16 3135 (-5000 5350)(-500 5350);
DOT 1 (-8500 3500);
DOT 1 (-8050 1900);
DOT 1 (-9400 1500);
DOT 1 (-8950 1100);
DOT 1 (-8950 1500);
DOT 1 (-8500 1100);
DOT 1 (-8500 1500);
DOT 1 (-9400 2300);
DOT 1 (-9400 3100);
DOT 1 (-8950 1900);
DOT 1 (-8950 2300);
DOT 1 (-8500 1900);
DOT 1 (-8500 2300);
DOT 1 (-8950 2700);
DOT 1 (-8950 3100);
DOT 1 (-8950 3500);
DOT 1 (-8500 2700);
DOT 1 (-8500 3100);
DOT 1 (-9400 3900);
DOT 1 (-9400 4675);
DOT 1 (-8950 3900);
DOT 1 (-8950 4275);
DOT 1 (-8950 4675);
DOT 1 (-8500 3900);
DOT 1 (-8500 4275);
DOT 1 (-8500 4675);
DOT 1 (-8050 1100);
DOT 1 (-8050 1500);
DOT 1 (-7600 1100);
DOT 1 (-8050 2300);
DOT 1 (-7600 1900);
DOT 1 (-7150 1900);
DOT 1 (-7600 2300);
DOT 1 (-7150 2300);
DOT 1 (-8050 2700);
DOT 1 (-8050 3100);
DOT 1 (-8050 3500);
DOT 1 (-7600 2700);
DOT 1 (-7600 3100);
DOT 1 (-7150 2700);
DOT 1 (-7150 3100);
DOT 1 (-7600 3500);
DOT 1 (-7150 3500);
DOT 1 (-6700 1900);
DOT 1 (-6700 2300);
DOT 1 (-6250 1900);
DOT 1 (-6250 2300);
DOT 1 (-6700 2700);
DOT 1 (-6700 3100);
DOT 1 (-6700 3500);
DOT 1 (-6250 2700);
DOT 1 (-6250 3100);
DOT 1 (-6250 3500);
DOT 1 (-4825 1500);
DOT 1 (-4375 1100);
DOT 1 (-4375 1500);
DOT 1 (-5800 1900);
DOT 1 (-5800 2300);
DOT 1 (-5400 1900);
DOT 1 (-5800 2700);
DOT 1 (-5800 3100);
DOT 1 (-5800 3500);
DOT 1 (-5400 2700);
DOT 1 (-5400 3500);
DOT 1 (-4825 2300);
DOT 1 (-4375 1900);
DOT 1 (-4375 2300);
DOT 1 (-4825 3100);
DOT 1 (-4375 2700);
DOT 1 (-4375 3100);
DOT 1 (-4375 3500);
DOT 1 (-8050 3900);
DOT 1 (-8050 4275);
DOT 1 (-8050 4675);
DOT 1 (-7600 3900);
DOT 1 (-7150 3900);
DOT 1 (-7600 4275);
DOT 1 (-7600 4675);
DOT 1 (-7150 4275);
DOT 1 (-7150 4675);
DOT 1 (-6700 3900);
DOT 1 (-6700 4275);
DOT 1 (-6700 4675);
DOT 1 (-6250 3900);
DOT 1 (-6250 4275);
DOT 1 (-6250 4675);
DOT 1 (-5800 3900);
DOT 1 (-5800 4275);
DOT 1 (-5800 4675);
DOT 1 (-5400 4275);
DOT 1 (-4825 3900);
DOT 1 (-4825 4675);
DOT 1 (-4375 3900);
DOT 1 (-4375 4275);
DOT 1 (-3925 1100);
DOT 1 (-3925 1500);
DOT 1 (-3475 1100);
DOT 1 (-3475 1500);
DOT 1 (-3025 1100);
DOT 1 (-3925 1900);
DOT 1 (-3925 2300);
DOT 1 (-3475 1900);
DOT 1 (-3475 2300);
DOT 1 (-3925 2700);
DOT 1 (-3925 3100);
DOT 1 (-3925 3500);
DOT 1 (-3475 2700);
DOT 1 (-3475 3100);
DOT 1 (-3475 3500);
DOT 1 (-3025 1900);
DOT 1 (-2575 1900);
DOT 1 (-3025 2300);
DOT 1 (-2575 2300);
DOT 1 (-2125 1900);
DOT 1 (-2125 2300);
DOT 1 (-3025 2700);
DOT 1 (-3025 3100);
DOT 1 (-2575 2700);
DOT 1 (-2575 3100);
DOT 1 (-3025 3500);
DOT 1 (-2575 3500);
DOT 1 (-2125 2700);
DOT 1 (-2125 3100);
DOT 1 (-2125 3500);
DOT 1 (-1675 1900);
DOT 1 (-1675 2300);
DOT 1 (-1225 1900);
DOT 1 (-1225 2300);
DOT 1 (-1675 2700);
DOT 1 (-1675 3100);
DOT 1 (-1675 3500);
DOT 1 (-1225 2700);
DOT 1 (-1225 3100);
DOT 1 (-1225 3500);
DOT 1 (-825 1900);
DOT 1 (-825 2700);
DOT 1 (-825 3500);
DOT 1 (-3925 3900);
DOT 1 (-3925 4275);
DOT 1 (-3925 4675);
DOT 1 (-3475 3900);
DOT 1 (-3475 4275);
DOT 1 (-3475 4675);
DOT 1 (-3025 3900);
DOT 1 (-2575 3900);
DOT 1 (-3025 4275);
DOT 1 (-3025 4675);
DOT 1 (-2575 4275);
DOT 1 (-2575 4675);
DOT 1 (-2125 3900);
DOT 1 (-2125 4275);
DOT 1 (-2125 4675);
DOT 1 (-1675 3900);
DOT 1 (-1675 4275);
DOT 1 (-1675 4675);
DOT 1 (-1225 3900);
DOT 1 (-1225 4275);
DOT 1 (-1225 4675);
DOT 1 (-825 4275);
DOT 1 (-4375 4675);
FORCENOTE
PVDDCR_CPU0_P1: 45PCS 22UF ON BOT
(-9525 5075) 0;
DISPLAY LEFT (-9525 5075);
DISPLAY 2.510638 (-9525 5075);
PAINT WHITE (-9525 5075);
FORCENOTE
5
(-7600 1550) 0;
DISPLAY LEFT (-7600 1550);
DISPLAY 1.021277 (-7600 1550);
PAINT SKYBLUE (-7600 1550);
FORCENOTE
5
(-7625 4775) 0;
DISPLAY LEFT (-7625 4775);
DISPLAY 1.021277 (-7625 4775);
PAINT SKYBLUE (-7625 4775);
FORCENOTE
10
(-5450 4775) 0;
DISPLAY LEFT (-5450 4775);
DISPLAY 1.021277 (-5450 4775);
PAINT SKYBLUE (-5450 4775);
FORCENOTE
5
(-3025 1575) 0;
DISPLAY LEFT (-3025 1575);
DISPLAY 1.021277 (-3025 1575);
PAINT SKYBLUE (-3025 1575);
FORCENOTE
5
(-3050 4800) 0;
DISPLAY LEFT (-3050 4800);
DISPLAY 1.021277 (-3050 4800);
PAINT SKYBLUE (-3050 4800);
FORCENOTE
10
(-875 4775) 0;
DISPLAY LEFT (-875 4775);
DISPLAY 1.021277 (-875 4775);
PAINT SKYBLUE (-875 4775);
FORCENOTE
PVDDCR_CPU1_P1: 45PCS 22UF ON BOT
(-4875 5100) 0;
DISPLAY LEFT (-4875 5100);
DISPLAY 2.510638 (-4875 5100);
PAINT WHITE (-4875 5100);
QUIT
